G04 ================== begin FILE IDENTIFICATION RECORD ==================*
G04 Layout Name:  12432-1.brd*
G04 Film Name:    L6*
G04 File Format:  Gerber RS274X*
G04 File Origin:  Cadence Allegro 16.2-S037*
G04 Origin Date:  Wed Oct 17 11:00:11 2012*
G04 *
G04 Layer:  VIA CLASS/L6*
G04 Layer:  PIN/L6*
G04 Layer:  ETCH/L6*
G04 Layer:  DRAWING FORMAT/LAYER_PCB_STORY*
G04 Layer:  DRAWING FORMAT/LAYER_L6*
G04 *
G04 Offset:    (0.00 0.00)*
G04 Mirror:    No*
G04 Mode:      Positive*
G04 Rotation:  0*
G04 FullContactRelief:  No*
G04 UndefLineWidth:     6.00*
G04 ================== end FILE IDENTIFICATION RECORD ====================*
%FSLAX35Y35*MOIN*%
%IR0*IPPOS*OFA0.00000B0.00000*MIA0B0*SFA1.00000B1.00000*%
%ADD14O,.103X.06*%
%ADD10C,.01*%
%ADD13C,.022*%
%ADD11C,.028*%
%ADD15C,.173*%
%ADD12C,.156*%
%ADD16C,.02*%
%ADD17C,.03*%
%ADD18C,.04*%
%ADD19C,.025*%
%ADD20C,.004*%
%ADD21C,.006*%
%ADD22C,.0045*%
%ADD24O,.12702X.08402*%
%ADD29C,.05204*%
%ADD23C,.04604*%
%ADD26C,.09706*%
%ADD28C,.18004*%
%ADD25C,.11506*%
%ADD27C,.17006*%
%ADD30C,.19704*%
G75*
%LPD*%
G75*
G36*
G01X403048Y194281D02*
X402958Y80026D01*
X382270Y59338D01*
X382178Y59345D01*
G03X380354Y55440I-179J-2295D01*
G02Y55160I-143J-140D01*
G03X384294Y53729I1645J-1610D01*
G01X384287Y53821D01*
X407550Y77084D01*
Y1730384D01*
X319170Y1818765D01*
G02X319453Y1819448I283J283D01*
G01X494804D01*
X773150Y1541101D01*
Y1535604D01*
X773080Y1535544D01*
G03X772903Y1532216I1497J-1748D01*
G02X772898Y1531661I-291J-275D01*
G03X776216Y1531630I1644J-1611D01*
G02X776221Y1532185I291J275D01*
G03X776074Y1535544I-1644J1611D01*
G01X776004Y1535604D01*
Y1542283D01*
X497872Y1820415D01*
G02X498155Y1821098I283J283D01*
G01X511934D01*
X545166Y1787866D01*
G02X544805Y1787190I-282J-284D01*
G03X546852Y1785143I-505J-2552D01*
G02X547528Y1785504I392J79D01*
G01X789211Y1543821D01*
X789204Y1543729D01*
G03X791497Y1541248I2295J-179D01*
G02X791697Y1541048I0J-200D01*
G03X794001Y1543352I2302J2D01*
G02X793801Y1543552I0J200D01*
G03X791320Y1545845I-2302J-2D01*
G01X791228Y1545838D01*
X774286Y1562780D01*
G02X774404Y1563427I283J283D01*
G03X775457Y1567290I-1077J2369D01*
G02X775524Y1567823I328J230D01*
G03X775777Y1568073I-1698J1972D01*
G02X776377I300J-264D01*
G03X780277I1950J1723D01*
G02X780877I300J-264D01*
G03X782975Y1567198I1950J1723D01*
G02X783374Y1566665I22J-399D01*
G03X784104Y1563846I2453J-869D01*
G02Y1563246I-264J-300D01*
G03X787550I1723J-1950D01*
G02Y1563846I264J300D01*
G03X785679Y1568394I-1723J1950D01*
G02X785280Y1568927I-22J399D01*
G03X780877Y1571519I-2453J869D01*
G02X780277I-300J264D01*
G03X776377I-1950J-1723D01*
G02X775777I-300J264D01*
G03X771697Y1568302I-1950J-1723D01*
G02X771630Y1567769I-328J-230D01*
G03X770958Y1566873I1697J-1973D01*
G02X770311Y1566755I-364J165D01*
G01X513116Y1823950D01*
X98740D01*
G02X98423Y1824595I0J400D01*
G03X98895Y1826179I-1823J1406D01*
G01X98888Y1826271D01*
X99288Y1826670D01*
X541867D01*
X852900Y1515637D01*
Y1479358D01*
X852830Y1479298D01*
G03X855824I1497J-1748D01*
G01X855754Y1479358D01*
Y1514152D01*
G02X856436Y1514435I400J0D01*
G01X859226Y1511646D01*
Y1433197D01*
X767782Y1341753D01*
Y1141416D01*
X768598Y1140600D01*
Y1129353D01*
X770836Y1127115D01*
G02X770767Y1126494I-283J-283D01*
G03X773322Y1126434I1233J-1944D01*
G01X773237Y1126494D01*
Y1126798D01*
X773846D01*
X776934Y1129887D01*
G02X777555Y1129818I283J-283D01*
G03X778002Y1129302I1944J1232D01*
G01X778072Y1129242D01*
Y1079546D01*
X896945Y960674D01*
X898690D01*
X898750Y960604D01*
G03X901239Y959920I1750J1496D01*
G02X901768Y959541I129J-379D01*
G01Y904670D01*
X767644Y770547D01*
Y741553D01*
X768572Y740625D01*
Y734858D01*
X768502Y734798D01*
G03X771496I1497J-1748D01*
G01X771426Y734858D01*
Y741807D01*
X770498Y742735D01*
Y757395D01*
G02X770937Y757793I400J0D01*
G03X773136Y762116I259J2589D01*
G02Y762648I299J266D01*
G03X773146Y762659I-1920J1756D01*
G02X773746I300J-264D01*
G03X777646I1950J1723D01*
G02X778246I300J-264D01*
G03X780344Y761784I1950J1723D01*
G02X780743Y761251I22J-399D01*
G03X781473Y758432I2453J-869D01*
G02Y757832I-264J-300D01*
G03X784919I1723J-1950D01*
G02Y758432I264J300D01*
G03X783048Y762980I-1723J1950D01*
G02X782649Y763513I-22J399D01*
G03X778246Y766105I-2453J869D01*
G02X777646I-300J264D01*
G03X773746I-1950J-1723D01*
G02X773146I-300J264D01*
G03X770937Y766971I-1950J-1723D01*
G02X770498Y767369I-39J398D01*
G01Y769365D01*
X786890Y785757D01*
G02X787572Y785474I282J-283D01*
G01Y737858D01*
X787502Y737798D01*
G03X789269Y733764I1497J-1748D01*
G02X789713Y733320I47J-397D01*
G03X791729Y735336I2286J-270D01*
G02X791285Y735780I-47J397D01*
G03X790496Y737798I-2286J269D01*
G01X790426Y737858D01*
Y786959D01*
X904385Y900918D01*
G02X905067Y900635I282J-283D01*
G01X905068Y737950D01*
Y721915D01*
X855776Y672624D01*
X854504D01*
X854444Y672694D01*
G03Y669700I-1748J-1497D01*
G01X854504Y669770D01*
X856958D01*
X906035Y718847D01*
G02X906718Y718564I283J-283D01*
G01Y576285D01*
G02X906009Y576031I-400J0D01*
G03Y572725I-2010J-1653D01*
G02X906718Y572471I309J-254D01*
G01Y546454D01*
X767276Y407013D01*
Y336959D01*
X771446Y332789D01*
Y328732D01*
X771376Y328672D01*
G03X771124Y325427I1497J-1749D01*
G02X771069Y324854I-304J-260D01*
G03X774248Y324547I1430J-1804D01*
G02X774303Y325120I304J260D01*
G03X774370Y328672I-1430J1804D01*
G01X774300Y328732D01*
Y333971D01*
X770130Y338141D01*
Y340436D01*
G02X770812Y340719I400J0D01*
G01X779091Y332440D01*
G02X779059Y331846I-283J-283D01*
G03X779002Y328302I1440J-1796D01*
G01X779072Y328242D01*
Y276459D01*
X835711Y219821D01*
X835704Y219729D01*
G03X837820Y221845I2295J-179D01*
G01X837728Y221838D01*
X781926Y277641D01*
Y328243D01*
X781996Y328303D01*
G03X782295Y328610I-1492J1752D01*
G02X782889Y328642I311J-251D01*
G01X790072Y321459D01*
Y295848D01*
X818297Y267624D01*
X849359D01*
X852112Y264871D01*
X852105Y264779D01*
G03X854221Y266895I2295J-179D01*
G01X854129Y266888D01*
X850541Y270476D01*
X819479D01*
X818073Y271882D01*
G02X818111Y272481I283J283D01*
G03X814881Y275711I-1411J1819D01*
G02X814282Y275673I-316J245D01*
G01X798491Y291465D01*
G02X798520Y292057I283J283D01*
G03X798596Y296021I-1647J2014D01*
G02Y296621I264J300D01*
G03Y300521I-1723J1950D01*
G02Y301121I264J300D01*
G03Y305021I-1723J1950D01*
G02Y305621I264J300D01*
G03X795150I-1723J1950D01*
G02Y305021I-264J-300D01*
G03Y301121I1723J-1950D01*
G02Y300521I-264J-300D01*
G03Y296621I1723J-1950D01*
G02Y296021I-264J-300D01*
G03X794859Y295718I1725J-1948D01*
G02X794267Y295689I-309J254D01*
G01X792926Y297030D01*
Y322641D01*
X771780Y343787D01*
Y356937D01*
G02X772219Y357335I400J0D01*
G03X774418Y361658I259J2589D01*
G02Y362190I299J266D01*
G03X774428Y362201I-1920J1756D01*
G02X775028I300J-264D01*
G03X778928I1950J1723D01*
G02X779528I300J-264D01*
G03X781626Y361326I1950J1723D01*
G02X782025Y360793I22J-399D01*
G03X782755Y357974I2453J-869D01*
G02Y357374I-264J-300D01*
G03X786201I1723J-1950D01*
G02Y357974I264J300D01*
G03X784330Y362522I-1723J1950D01*
G02X783931Y363055I-22J399D01*
G03X779528Y365647I-2453J869D01*
G02X778928I-300J264D01*
G03X775028I-1950J-1723D01*
G02X774428I-300J264D01*
G03X772219Y366513I-1950J-1723D01*
G02X771780Y366911I-39J398D01*
G01Y405147D01*
X787890Y421257D01*
G02X788572Y420974I282J-283D01*
G01Y338358D01*
X788502Y338298D01*
G03X789137Y334416I1497J-1748D01*
G02X789359Y333898I-150J-371D01*
G03X792361Y335184I2140J-848D01*
G02X792139Y335702I150J371D01*
G03X791496Y338298I-2140J848D01*
G01X791426Y338358D01*
Y422459D01*
X912870Y543904D01*
Y1496202D01*
X868765Y1540307D01*
G02X868822Y1540921I283J283D01*
G03X865623Y1544120I-1299J1900D01*
G02X865009Y1544063I-331J226D01*
G01X562582Y1846491D01*
G02X562865Y1847173I283J282D01*
G01X800805D01*
X966174Y1681805D01*
Y1652909D01*
X966104Y1652849D01*
G03X967748Y1648803I1496J-1749D01*
G02X968174Y1648404I26J-399D01*
G01Y1640108D01*
X968103Y1640048D01*
G03X968017Y1639972I1481J-1762D01*
G02X967359Y1640149I-275J290D01*
G03X962963Y1638781I-2209J-649D01*
G02X962453Y1638278I-380J-125D01*
G03X963889Y1636821I-751J-2176D01*
G02X964399Y1637324I380J125D01*
G03X966733Y1637828I752J2176D01*
G02X967391Y1637651I275J-290D01*
G03X971096Y1640049I2209J649D01*
G01X971026Y1640109D01*
Y1643801D01*
G02X971446Y1644201I400J0D01*
G03X973054Y1648249I112J2299D01*
G01X972984Y1648309D01*
Y1668069D01*
G02X973476Y1668459I400J0D01*
G03X975124Y1668691I525J2241D01*
G02X975717Y1668292I196J-349D01*
G03X976876Y1670009I2283J-292D01*
G02X976283Y1670408I-196J349D01*
G03X973476Y1672941I-2283J292D01*
G02X972984Y1673331I-92J390D01*
G01Y1683707D01*
X803068Y1853623D01*
X147556D01*
G02X147273Y1854306I0J400D01*
G01X151090Y1858124D01*
X831405D01*
X854543Y1881262D01*
X854635Y1881255D01*
G03X852519Y1883371I179J2295D01*
G01X852526Y1883279D01*
X830223Y1860976D01*
X695409D01*
G02X695126Y1861659I0J400D01*
G01X768903Y1935437D01*
G02X769528Y1935360I282J-283D01*
G03X773144Y1938160I1971J1190D01*
G02Y1938440I143J140D01*
G03X772939Y1941846I-1645J1610D01*
G02X772907Y1942440I251J311D01*
G01X778090Y1947624D01*
X790690D01*
X790750Y1947554D01*
G03Y1950546I1749J1496D01*
G01X790690Y1950476D01*
X776908D01*
X691184Y1864752D01*
X140701D01*
G02X140301Y1865152I0J400D01*
G03X137747Y1867439I-2302J-1D01*
G02X137420Y1868120I-44J398D01*
G01X138451Y1869150D01*
X271698D01*
X334874Y1932326D01*
Y1947380D01*
X334391Y1947862D01*
X334398Y1947954D01*
G03X330186Y1946859I-2295J179D01*
G01X330190Y1946854D01*
X330210Y1946822D01*
X330245Y1946710D01*
X330171Y1946555D01*
X330138Y1946527D01*
G03X329336Y1944498I1484J-1760D01*
G01X279663Y1894825D01*
G02X279052Y1894879I-283J283D01*
G03X271726Y1880744I-7395J-5133D01*
G02X272012Y1880061I3J-400D01*
G01X265604Y1873654D01*
X231942D01*
G02X231625Y1874297I0J400D01*
G03X229976Y1877995I-1825J1403D01*
G02X229724Y1878677I31J399D01*
G01X246908Y1895860D01*
G02X247547Y1895758I282J-283D01*
G03X250642Y1898853I2053J1042D01*
G02X250540Y1899492I181J357D01*
G01X264677Y1913630D01*
G02X265232Y1913640I283J-283D01*
G03X269175Y1916977I1767J1910D01*
G01X269086Y1917113D01*
X279187Y1927215D01*
G02X279807Y1927148I283J-283D01*
G03X280559Y1926383I2192J1402D01*
G02Y1925717I-222J-333D01*
G03Y1921383I1440J-2167D01*
G02Y1920717I-222J-333D01*
G03X283439I1440J-2167D01*
G02Y1921383I222J333D01*
G03Y1925717I-1440J2167D01*
G02Y1926383I222J333D01*
G03X284418Y1927590I-1439J2168D01*
G02X284894Y1927829I372J-147D01*
G03X285313Y1932345I605J2221D01*
G02X284998Y1933026I-32J399D01*
G01X286426Y1934453D01*
Y1945885D01*
G03X286736Y1946181I-1428J1806D01*
G02X287286Y1946233I302J-262D01*
G03X286972Y1949552I1423J1809D01*
G02X286422Y1949500I-302J262D01*
G03X283502Y1945943I-1422J-1809D01*
G01X283572Y1945883D01*
Y1935635D01*
X269605Y1921668D01*
G02X269013Y1921697I-283J283D01*
G03X268722Y1922000I-2016J-1645D01*
G02Y1922600I264J300D01*
G03Y1926500I-1723J1950D01*
G02Y1927100I264J300D01*
G03Y1931000I-1723J1950D01*
G02Y1931600I264J300D01*
G03X268646Y1935564I-1723J1950D01*
G02X268617Y1936156I254J309D01*
G01X289584Y1957124D01*
X308190D01*
X308200Y1956934D01*
G03X310320Y1959345I2299J116D01*
G01X310228Y1959338D01*
X309590Y1959976D01*
X296491D01*
G02X296159Y1960599I0J400D01*
G03X295722Y1964000I-2160J1451D01*
G02Y1964600I264J300D01*
G03Y1968500I-1723J1950D01*
G02Y1969100I264J300D01*
G03X292049Y1972773I-1723J1950D01*
G02X291449I-300J264D01*
G03X287776Y1969100I-1950J-1723D01*
G02Y1968500I-264J-300D01*
G03X288059Y1964383I1723J-1950D01*
G02Y1963717I-222J-333D01*
G03X287621Y1959749I1440J-2167D01*
G02X287615Y1959189I-289J-277D01*
G01X256072Y1927647D01*
Y1912856D01*
G03X255870Y1909423I1427J-1806D01*
G02Y1908858I-283J-283D01*
G01X234656Y1887643D01*
G02X233992Y1887804I-283J283D01*
G03X230261Y1888812I-2192J-704D01*
G02X229671Y1888873I-267J298D01*
G03X225519Y1887334I-1857J-1360D01*
G01X225526Y1887242D01*
X215237Y1876954D01*
X135216D01*
X125915Y1867652D01*
X58396D01*
X58299Y1867750D01*
X51399D01*
X30219Y1846570D01*
X30111Y1846594D01*
G03X28592Y1846420I-512J-2244D01*
G01X28551Y1846400D01*
X3800D01*
X3000Y1847200D01*
Y1944500D01*
X3799Y1945299D01*
X3937Y1945197D01*
G03X3885Y1948863I1366J1853D01*
G01X3746Y1948754D01*
X3000Y1949500D01*
Y1988000D01*
X4000Y1989000D01*
X1029000D01*
X1029999Y1988001D01*
Y1956500D01*
X1030000Y1956499D01*
Y1950500D01*
X1029999D01*
Y1696499D01*
X1028421Y1694921D01*
G02X1027741Y1695159I-283J283D01*
G03X1018344Y1685762I-8450J-947D01*
G02X1018582Y1685082I-45J-397D01*
G01X1015850Y1682350D01*
Y1674050D01*
X1015800Y1674000D01*
Y1624800D01*
X1013000Y1622000D01*
X989000D01*
X984500Y1617500D01*
Y1610000D01*
X989000Y1605500D01*
X1011000D01*
X1016000Y1600500D01*
Y1430000D01*
X1020500Y1425500D01*
X1028000D01*
X1030000Y1423500D01*
Y1270551D01*
X1029999Y1270550D01*
Y4000D01*
X1029500Y3501D01*
Y3500D01*
X1029000Y3000D01*
X4000D01*
X3000Y4000D01*
Y366551D01*
X4999Y368550D01*
X24999D01*
X28146Y371697D01*
X28223Y371701D01*
G03X29111Y376068I-123J2299D01*
G01X28999Y376123D01*
Y410650D01*
X30199Y411850D01*
Y413550D01*
X28999Y414750D01*
Y415493D01*
X29175Y415514D01*
G03X30281Y415958I-275J2286D01*
G01X30420Y416063D01*
X33612Y412871D01*
X33605Y412779D01*
G03X35721Y414895I2295J-179D01*
G01X35629Y414888D01*
X33050Y417467D01*
Y424651D01*
G02X33733Y424934I400J0D01*
G01X81544Y377124D01*
X244508D01*
X280449Y341183D01*
G02X280363Y340552I-283J-283D01*
G03X281678Y336255I1136J-2002D01*
G01X281770Y336262D01*
X283633Y334398D01*
X307584D01*
X374243Y401057D01*
X380100Y395200D01*
X381262D01*
G02X381545Y394517I0J-400D01*
G01X326770Y339742D01*
X326678Y339749D01*
G03X324786Y335916I-179J-2295D01*
G01X324810Y335889D01*
X324863Y335754D01*
X324810Y335619D01*
X324786Y335592D01*
G03X328794Y334233I1713J-1538D01*
G01X328787Y334325D01*
X389662Y395200D01*
X394772D01*
Y389361D01*
X287952Y282540D01*
X253097D01*
G02X252698Y282964I0J400D01*
G03X248102I-2298J136D01*
G02X247703Y282540I-399J-24D01*
G01X227107D01*
X227047Y282610D01*
G03Y279618I-1749J-1496D01*
G01X227107Y279688D01*
X236987D01*
G02X237374Y279186I0J-400D01*
G03X241826I2226J-586D01*
G02X242213Y279688I387J102D01*
G01X289134D01*
X395740Y386293D01*
G02X396423Y386010I283J-283D01*
G01X396422Y279688D01*
Y198491D01*
X297770Y99838D01*
X297678Y99845D01*
G03X299794Y97729I-179J-2295D01*
G01X299787Y97821D01*
X339390Y137423D01*
G02X340073Y137140I283J-283D01*
G01X340072Y97821D01*
Y68918D01*
X340002Y68858D01*
G03X339980Y65381I1497J-1748D01*
G02Y64779I-264J-301D01*
G03X343794Y63229I1519J-1729D01*
G01X343787Y63321D01*
X345300Y64834D01*
Y97563D01*
G02X345740Y97961I400J0D01*
G03X348166Y99110I259J2589D01*
G02X348832I333J-222D01*
G03X353166I2167J1440D01*
G02X353832I333J-222D01*
G03X358166I2167J1440D01*
G02X358832I333J-222D01*
G03Y101990I2167J1440D01*
G02X358166I-333J222D01*
G03X353832I-2167J-1440D01*
G02X353166I-333J222D01*
G03X348832I-2167J-1440D01*
G02X348166I-333J222D01*
G03X345740Y103139I-2167J-1440D01*
G02X345300Y103537I-40J398D01*
G01Y110646D01*
G02X345940Y110967I400J1D01*
G03X349449Y111327I1559J2083D01*
G02X350049I300J-264D01*
G03X353949I1950J1723D01*
G02X354549I300J-264D01*
G03X358449I1950J1723D01*
G02X359049I300J-264D01*
G03Y114773I1950J1723D01*
G02X358449I-300J264D01*
G03X354549I-1950J-1723D01*
G02X353949I-300J264D01*
G03X350049I-1950J-1723D01*
G02X349449I-300J264D01*
G03X345940Y115133I-1950J-1723D01*
G02X345300Y115454I-240J320D01*
G01X345332Y137532D01*
X402365Y194564D01*
G02X403048Y194281I283J-283D01*
G37*
G36*
G01X4499Y861050D02*
X3000Y862549D01*
Y1350551D01*
X4499Y1352050D01*
X18690D01*
X18704Y1351866D01*
G03X21967Y1354138I2295J184D01*
G01X21935Y1354153D01*
X21769Y1354320D01*
X21999Y1354550D01*
Y1393500D01*
X27000Y1398501D01*
Y1404500D01*
X26500Y1405000D01*
X26499D01*
X21999Y1409500D01*
Y1521685D01*
G02X22665Y1521983I400J0D01*
G03X24378Y1521405I1533J1717D01*
G01X24470Y1521412D01*
X27637Y1518244D01*
X29297D01*
G02X29697Y1517845I0J-400D01*
G03X33898Y1516545I2302J1D01*
G02X34511Y1516602I330J-226D01*
G01X38198Y1512915D01*
Y1390785D01*
G02X37515Y1390502I-400J0D01*
G01X35802Y1392215D01*
Y1394125D01*
X33898Y1396028D01*
X32745D01*
X32702Y1396170D01*
G03X28745Y1394010I-2202J-670D01*
G02X28449Y1393351I-305J-259D01*
G03X29551Y1389002I50J-2301D01*
G02X30118Y1388755I182J-356D01*
G03X34515Y1388650I2215J628D01*
G02X35177Y1388805I379J-128D01*
G01X36548Y1387435D01*
Y1349178D01*
G02X35865Y1348895I-400J0D01*
G01X27288Y1357471D01*
X27295Y1357563D01*
G03X25179Y1355447I-2295J179D01*
G01X25271Y1355454D01*
X34874Y1345851D01*
Y1052661D01*
X17030Y1034817D01*
Y885308D01*
X27498Y874840D01*
Y864217D01*
G02X27033Y863822I-400J0D01*
G03X25916Y863728I-371J-2272D01*
G02X25418Y863950I-130J378D01*
G03X21444Y861687I-2119J-900D01*
G02X21122Y861050I-322J-237D01*
G01X4499D01*
G37*
G36*
G01X29665Y419971D02*
G03X28463Y420060I-765J-2171D01*
G01X28359Y420040D01*
X27611Y420788D01*
G02X27672Y421404I283J283D01*
G03X28144Y424823I-1273J1918D01*
G02X28154Y425095I152J131D01*
G03X24779Y425219I-1630J1625D01*
G02X24769Y424947I-152J-131D01*
G03X24481Y424595I1629J-1626D01*
G02X23865Y424534I-333J222D01*
G01X21349Y427050D01*
Y540000D01*
X22849Y541500D01*
X23474D01*
Y536509D01*
X27090Y532893D01*
Y532002D01*
G02X26676Y531603I-400J1D01*
G03X24903Y527745I-77J-2301D01*
G02Y527205I-295J-270D01*
G03X26676Y523347I1696J-1557D01*
G02X27090Y522948I14J-400D01*
G01Y513893D01*
X30198Y510785D01*
Y420349D01*
G02X29665Y419971I-400J0D01*
G37*
G36*
G01X22694Y575355D02*
X21999Y576050D01*
Y816050D01*
X27191Y821242D01*
G02X27874Y820959I283J-283D01*
G01Y806051D01*
X24048Y802225D01*
Y771735D01*
X28148Y767634D01*
Y748466D01*
X24374Y744691D01*
Y705427D01*
X30398Y699403D01*
Y692691D01*
X29674Y691967D01*
Y684897D01*
G02X29041Y684571I-400J-1D01*
G03Y680829I-1341J-1871D01*
G02X29674Y680503I233J-325D01*
G01Y673288D01*
G02X29039Y672964I-400J0D01*
G03X25991Y669544I-1352J-1863D01*
G02Y669004I-295J-270D01*
G03X29383I1696J-1557D01*
G02Y669544I295J270D01*
G03X29449Y669619I-1695J1558D01*
G02X30038Y669645I306J-257D01*
G01X31398Y668285D01*
Y647691D01*
X31110Y647404D01*
Y645386D01*
X31108Y645384D01*
Y627942D01*
X31110Y627940D01*
Y614228D01*
X29433Y612550D01*
G02X28802Y612636I-283J283D01*
G03X25664Y609498I-2002J-1136D01*
G02X25750Y608867I-197J-348D01*
G01X23376Y606494D01*
Y575638D01*
G02X22694Y575355I-400J0D01*
G37*
G36*
G01X46272Y559560D02*
G02X45590Y559277I-400J0D01*
G01X38787Y566079D01*
X38794Y566171D01*
G03X35840Y568556I-2295J179D01*
G02X35326Y568939I-114J383D01*
G01Y572141D01*
X30040Y577425D01*
X30097Y577551D01*
G03X26832Y580484I-2097J949D01*
G02X26230Y580829I-202J345D01*
G01Y591552D01*
G02X26952Y591788I400J-1D01*
G03X30446Y594767I1856J1362D01*
G02X30438Y595039I143J140D01*
G03X26936Y598028I-1738J1510D01*
G02X26230Y598285I-306J257D01*
G01Y605312D01*
X28634Y607716D01*
G02X29313Y607384I282J-283D01*
G03X30231Y605250I2285J-282D01*
G02X30279Y604979I-119J-161D01*
G03X34030Y602313I1921J-1269D01*
G02X34748Y602070I318J-243D01*
G01Y576778D01*
X41244Y570282D01*
G02X41204Y569681I-283J-283D01*
G03X42458Y565552I1395J-1831D01*
G01X42534Y565548D01*
X46272Y561809D01*
Y559560D01*
G37*
G36*
G01X80532Y490816D02*
G02X78819Y490106I-1714J1713D01*
G01X65321D01*
X65280Y490251D01*
G03X64293Y491564I-2212J-636D01*
G02X64224Y492185I214J338D01*
G01X99000Y526962D01*
Y539406D01*
X91980Y546426D01*
X74309D01*
X74249Y546496D01*
G03X70932Y546685I-1749J-1496D01*
G02X70266Y546907I-272J293D01*
G03X68179Y544205I-2266J-407D01*
G01X68271Y544212D01*
X70909Y541574D01*
X90464D01*
X94498Y537540D01*
Y529315D01*
X93560Y528377D01*
G02X92879Y528701I-283J283D01*
G03X92900Y529111I-3942J407D01*
G01Y532942D01*
X92901D01*
G03X91995Y535135I-3102J2D01*
G01X91684Y535446D01*
G03X89491Y536352I-2191J-2196D01*
G01X88483D01*
X88449Y536509D01*
G03X84552Y534417I-2250J-484D01*
G02Y533858I-286J-279D01*
G03X88157Y531040I1647J-1609D01*
G02X88898Y530830I341J-210D01*
G01Y529129D01*
X87808Y528040D01*
X87307Y527537D01*
G02X87099Y527451I-208J208D01*
G01X83456D01*
G02X82298Y527931I0J1638D01*
G01X74172Y536057D01*
G03X69999Y537786I-4174J-4173D01*
G01X62295D01*
X62266Y537951D01*
G03X58312Y535984I-2267J-401D01*
G02Y535712I-147J-136D01*
G03X57707Y533978I1691J-1562D01*
G02X57026Y533666I-399J-29D01*
G01X55178Y535514D01*
Y562951D01*
X48602Y569526D01*
X46034D01*
X37600Y577960D01*
Y608848D01*
G02X38000Y609248I400J0D01*
G03X39539Y609839I-1J2302D01*
G02X39811Y609835I134J-149D01*
G03X40128Y609581I1592J1662D01*
G02X40192Y609317I-111J-167D01*
G03X43583Y606354I2010J-1121D01*
G02X43863Y606314I120J-160D01*
G03X47450Y606204I1838J1386D01*
G01X47510Y606274D01*
X69951D01*
X77858Y598366D01*
X102274D01*
Y544909D01*
X103712Y543471D01*
X103705Y543379D01*
G03X107564Y541511I2295J-179D01*
G02X107836I136J-147D01*
G03X109759Y540926I1564J1689D01*
G02X110222Y540531I63J-395D01*
G01Y521127D01*
G02X109782Y520066I-1501J1D01*
G01X80532Y490816D01*
G37*
G36*
G01X83553Y607339D02*
X128780Y652566D01*
X152414D01*
X153098Y651882D01*
Y642808D01*
X152798Y642507D01*
Y608937D01*
X143298Y599437D01*
Y569411D01*
X141987Y568100D01*
X141876Y568129D01*
G03X139661Y564284I-576J-2229D01*
G02X139607Y563677I-285J-281D01*
G03X141190Y559512I1333J-1877D01*
G02X141517Y558831I44J-398D01*
G01X138488Y555802D01*
X138406D01*
G03X137977Y555760I9J-2302D01*
G02X137500Y556152I-77J393D01*
G01X137501Y578497D01*
G03X134790Y585041I-9255J0D01*
G03X130178Y586952I-4613J-4612D01*
G01X123099D01*
G02X121900Y588150I-1J1198D01*
G01Y616715D01*
X121945Y616770D01*
G03X122300Y617776I-1246J1005D01*
G01Y619776D01*
G03X121945Y620782I-1601J1D01*
G01X121900Y620837D01*
Y623229D01*
G02X122990Y625859I3720J-1D01*
G02X123448Y626049I458J-458D01*
G01Y626048D01*
X130668D01*
G03X133590Y627259I-1J4133D01*
G03X135000Y630664I-3405J3405D01*
G01Y639534D01*
G02X135239Y640110I815J0D01*
G01X139839Y644710D01*
G02X140415Y644948I575J-576D01*
G01X141967D01*
X142005Y644797D01*
G03X145885Y646964I2233J559D01*
G02Y647523I286J280D01*
G03X141936Y649150I-1647J1608D01*
G01X141934Y648960D01*
X140414D01*
G03X137002Y647547I0J-4826D01*
G01X134267Y644812D01*
G02X133655Y645064I-221J333D01*
G03X130274Y646608I-2255J-464D01*
G02X130002Y646684I-98J174D01*
G03X129125Y643542I-2003J-1134D01*
G02X129397Y643466I98J-174D01*
G03X131203Y642306I2004J1134D01*
G02X131554Y641799I-34J-399D01*
G03X130990Y639534I4261J-2264D01*
G01Y630665D01*
G02X130753Y630095I-805J0D01*
G02X130667Y630060I-85J86D01*
G01X123447D01*
G03X120153Y628696I0J-4659D01*
G03X117890Y623230I5468J-5465D01*
G01Y588150D01*
G03X123099Y582940I5210J0D01*
G01X130177D01*
G02X131953Y582204I0J-2511D01*
G02X133489Y578497I-3707J-3708D01*
G03X133490Y578444I1409J0D01*
G01Y540403D01*
G03X133489Y540350I1408J-53D01*
G02X131780Y536224I-5835J0D01*
G01X129352Y533797D01*
X114571Y519016D01*
G02X113969Y519470I-221J334D01*
G03X114224Y521126I-5248J1656D01*
G01Y625569D01*
G02X115090Y627659I2956J0D01*
G01X121941Y634510D01*
X122154Y634724D01*
G02X122699Y634948I544J-548D01*
G01X123272D01*
X123318Y634813D01*
G03X127188Y637114I2181J737D01*
G02Y637386I147J136D01*
G03X123204Y639135I-1689J1564D01*
G01X123190Y638952D01*
X121298D01*
Y638743D01*
X121162Y638697D01*
G03X119320Y637552I1534J-4522D01*
G01X119106Y637337D01*
X112259Y630490D01*
G03X110221Y625569I4921J-4920D01*
G01X110222D01*
Y545869D01*
G02X109759Y545474I-400J0D01*
G03X109221Y545495I-358J-2274D01*
G01X109129Y545488D01*
X107426Y547191D01*
Y589509D01*
X109226Y591309D01*
Y604215D01*
X109233Y604239D01*
G03X104705Y604621I-2233J561D01*
G01X104712Y604529D01*
X103909Y603726D01*
X79291D01*
X71691Y611326D01*
X49935D01*
X49919Y611508D01*
G03X45476Y610478I-2293J-208D01*
G02X45191Y609945I-374J-143D01*
G03X44320Y609541I512J-2244D01*
G02X44040Y609581I-120J160D01*
G03X43474Y610114I-1839J-1385D01*
G01X43385Y610281D01*
X43410Y610378D01*
G03X39860Y613211I-2010J1122D01*
G02X39588Y613215I-134J149D01*
G03X38000Y613852I-1590J-1665D01*
G02X37600Y614252I0J400D01*
G01Y615683D01*
X46326Y624409D01*
Y629563D01*
X46830Y630067D01*
X46922Y630060D01*
G03X44806Y632176I179J2295D01*
G01X44813Y632084D01*
X43474Y630745D01*
Y628284D01*
G02X43020Y627888I-400J0D01*
G03X41963Y627785I-311J-2281D01*
G01X41898Y627774D01*
X41714Y627895D01*
G03X39421Y629279I-2114J-911D01*
G01X39329Y629272D01*
X37862Y630740D01*
Y631098D01*
G02X38267Y631498I400J0D01*
G03X40363Y632778I33J2302D01*
G02X40618Y632874I179J-89D01*
G03X41104Y637268I882J2126D01*
G02X40636Y637662I-68J394D01*
G01Y640138D01*
G02X41104Y640532I400J0D01*
G03X43530Y643885I396J2268D01*
G02X43883Y644474I353J189D01*
G01X46565D01*
G02X46925Y643900I0J-400D01*
G03X47503Y641151I2074J-999D01*
G01X47572Y641091D01*
Y637910D01*
X50212Y635271D01*
X50205Y635179D01*
G03X52321Y637295I2295J-179D01*
G01X52229Y637288D01*
X50426Y639092D01*
Y641091D01*
X50495Y641151D01*
G03X51287Y642646I-1496J1750D01*
G01X51307Y642824D01*
X66708D01*
X67258Y643374D01*
X67259D01*
X203233Y779348D01*
X294973D01*
G02X295256Y778665I0J-400D01*
G01X176152Y659561D01*
Y502141D01*
X172608Y498597D01*
G02X171926Y498880I-282J283D01*
G01Y501141D01*
X160426Y512641D01*
Y574298D01*
G02X160825Y574698I400J0D01*
G03Y579302I0J2302D01*
G02X160426Y579702I1J400D01*
G01Y587459D01*
X167044Y594078D01*
Y660973D01*
X165591Y662426D01*
X124009D01*
X90059Y628476D01*
X84308D01*
X84248Y628546D01*
G03Y625554I-1749J-1496D01*
G01X84308Y625624D01*
X88744D01*
G02X89027Y624941I0J-400D01*
G01X85539Y621452D01*
X81924D01*
X81897Y621461D01*
G03Y617041I-646J-2210D01*
G01X81924Y617050D01*
X86070D01*
G02X86353Y616367I0J-400D01*
G01X79050Y609063D01*
Y607922D01*
X79041Y607895D01*
G03X83553Y607256I2210J-645D01*
G01Y607339D01*
G37*
G36*
G01X34030Y605107D02*
G03X33567Y605562I-1829J-1398D01*
G02X33519Y605833I119J161D01*
G03X31316Y609387I-1921J1269D01*
G02X30984Y610066I-49J397D01*
G01X33964Y613046D01*
X33963Y626879D01*
G02X34646Y627162I400J0D01*
G01X38201Y623608D01*
X40524D01*
G02X40807Y622925I0J-400D01*
G01X34748Y616865D01*
Y605350D01*
G02X34030Y605107I-400J0D01*
G37*
G36*
G01X52688Y695469D02*
G02X53066Y695500I381J-2324D01*
G01X64428Y695499D01*
G03X69639Y697145I0J9072D01*
G01X69776Y697242D01*
X69853Y697165D01*
X84248Y711560D01*
G03X86500Y716999I-5442J5439D01*
G01Y786134D01*
G02X87183Y786417I400J0D01*
G01X88100Y785500D01*
X107568D01*
X108669Y784399D01*
X324178D01*
G02X324320Y784057I1J-200D01*
G01X324113Y783850D01*
X201366D01*
X163593Y746078D01*
G02X162911Y746389I-283J283D01*
G03X158414Y741892I-4840J343D01*
G02X158725Y741210I28J-399D01*
G01X83126Y665611D01*
G02X82496Y665695I-283J283D01*
G03X78889Y666195I-1997J-1145D01*
G02X78609I-140J143D01*
G03Y662905I-1610J-1645D01*
G02X78889I140J-143D01*
G03X79354Y662553I1611J1645D01*
G02X79438Y661923I-199J-347D01*
G01X64842Y647326D01*
X41428D01*
X39589Y645488D01*
G02X38906Y645771I-283J283D01*
G01Y666089D01*
X41926Y669109D01*
Y697425D01*
X31126Y708225D01*
Y741009D01*
X34902Y744784D01*
Y786316D01*
X34820Y786397D01*
G02X35132Y787079I283J283D01*
G03X34215Y791405I168J2296D01*
G02X33626Y791758I-189J353D01*
G01Y792887D01*
G02X34253Y793216I400J0D01*
G03X37369Y793689I1306J1896D01*
G02X37966Y793725I314J-247D01*
G01X39639Y792052D01*
G03X40274Y792145I283J283D01*
G02X40803Y792799I2024J-1096D01*
G01X40872Y792859D01*
Y793656D01*
G03X40322Y794026I-400J0D01*
G02X37794Y794562I-869J2132D01*
G03X37590Y796195I-2235J550D01*
G02X37865Y796775I353J188D01*
G03X39044Y800661I-449J2258D01*
G02Y801226I283J282D01*
G01X41993Y804176D01*
X44210D01*
G02X44606Y803722I0J-400D01*
G03X44820Y802400I2281J-309D01*
G02X44399Y801829I-359J-176D01*
G03X43519Y797313I-353J-2275D01*
G01X43674Y797277D01*
Y794909D01*
X43604Y794849D01*
G03X46596I1496J-1749D01*
G01X46526Y794909D01*
Y796709D01*
X49759Y799942D01*
G02X50427Y799767I283J-283D01*
G03X50812Y799476I385J109D01*
G01X54016D01*
G03X54282Y799577I0J400D01*
G02X54804Y799584I265J-299D01*
G03X55750Y803590I1477J1766D01*
G02X55286Y803830I-93J389D01*
G03X55194Y803968I-372J-148D01*
G02X55070Y804098I1602J1653D01*
G03X54878Y804219I-300J-264D01*
G02X54704Y804887I109J385D01*
G01X65229Y815412D01*
X65321Y815405D01*
G03X65164Y819977I180J2295D01*
G02X64706Y820362I-58J396D01*
G03X62741Y818023I-2301J-62D01*
G02X63199Y817638I58J-396D01*
G03X63205Y817521I2301J59D01*
G01X63212Y817429D01*
X53490Y807708D01*
G02X52896Y807740I-283J283D01*
G03X52728Y807927I-1794J-1443D01*
G02Y808493I283J283D01*
G01X53626Y809391D01*
Y813048D01*
G02X54034Y813448I400J0D01*
G03X55731Y817347I40J2302D01*
G01X55676Y817406D01*
Y844146D01*
X62002Y850472D01*
Y1009100D01*
X62500D01*
X62600Y1009000D01*
X66278D01*
X66304Y1008993D01*
G03X67696I696J2507D01*
G01X67722Y1009000D01*
X75654D01*
X78541Y1006113D01*
G03X78580Y1006078I286J280D01*
G02X78686Y1005567I-244J-317D01*
G03X79151Y1002746I2013J-1117D01*
G02Y1002154I-269J-296D01*
G03X82829Y999576I1548J-1704D01*
G01X82880Y999700D01*
X95848D01*
Y989994D01*
G02X94752Y987347I-3743J0D01*
G01X84697Y977292D01*
G03X82298Y971501I5792J-5792D01*
G01Y947161D01*
G02X81959Y946341I-1159J-1D01*
G01X79751Y944133D01*
G03X77998Y939901I4234J-4233D01*
G01Y932924D01*
G03X78944Y929541I6524J1D01*
G01X79025Y929407D01*
X78918Y929300D01*
X81409Y926809D01*
G02X82498Y924181I-2628J-2628D01*
G01X82497Y845124D01*
X76590D01*
X76050Y844584D01*
X76213Y844421D01*
X76048Y844256D01*
X76018Y844241D01*
G03X74830Y843421I2132J-4359D01*
G02X74289Y843415I-274J292D01*
G03X74022Y843518I-268J-297D01*
G01X72196D01*
G03X72112Y843509I0J-400D01*
G02X71654Y843760I-83J391D01*
G03X67844Y841350I-2155J-810D01*
G02X67749Y840722I-288J-278D01*
G03X70515Y840306I1111J-2016D01*
G02X70610Y840934I288J278D01*
G03X71040Y841239I-1108J2018D01*
G01X71181Y841366D01*
X72111Y840436D01*
Y839455D01*
X72658Y838909D01*
G03X73024Y838801I282J283D01*
G02X73492Y838522I84J-391D01*
G03X80699Y835753I4658J1360D01*
G02X81235Y835644I210J-340D01*
G03X81562Y835476I326J232D01*
G01X82498D01*
Y819179D01*
G02X81861Y818857I-400J0D01*
G03Y815143I-1361J-1857D01*
G02X82498Y814821I237J-322D01*
G01Y717000D01*
G02X81417Y714391I-3691J1D01*
G01X68013Y700987D01*
G02X64429Y699502I-3585J3584D01*
G01X52953D01*
G02X52578Y699533I6J2351D01*
G03X48663Y697582I-2278J-333D01*
G02X48672Y697310I-142J-141D01*
G03X52688Y695469I1738J-1509D01*
G37*
G36*
G01X29416Y770402D02*
X26900Y772917D01*
Y780848D01*
G02X27300Y781248I400J0D01*
G03X29489Y784259I-1J2302D01*
G01X29451Y784375D01*
X29679Y784603D01*
X30098Y784184D01*
Y770685D01*
G02X29416Y770402I-400J0D01*
G37*
G36*
G01X30351Y863307D02*
X30350Y876022D01*
X19882Y886490D01*
Y1023318D01*
G02X20565Y1023601I400J0D01*
G01X36548Y1007619D01*
Y868538D01*
X31033Y863024D01*
G02X30351Y863307I-282J283D01*
G37*
G36*
G01X37515Y1010687D02*
X28331Y1019870D01*
G02X28653Y1020551I283J283D01*
G03X37446Y1025221I878J8959D01*
G02X38198Y1025031I352J-190D01*
G01Y1010970D01*
G02X37515Y1010687I-400J0D01*
G37*
G36*
G01X37446Y1033799D02*
G03X27988Y1038379I-7915J-4289D01*
G02X27637Y1039056I-68J394D01*
G01X37515Y1048933D01*
G02X38198Y1048650I283J-283D01*
G01Y1033989D01*
G02X37446Y1033799I-400J0D01*
G37*
G36*
G01X38300Y1517813D02*
G02X37617Y1517530I-400J0D01*
G01X34229Y1520918D01*
X34251Y1521024D01*
G03X34134Y1522361I-2252J477D01*
G02X34505Y1522910I371J149D01*
G01X35410D01*
X38300Y1520021D01*
Y1517813D01*
G37*
G36*
G01X28819Y1521098D02*
X26487Y1523429D01*
X26494Y1523521D01*
G03X22665Y1525417I-2295J179D01*
G02X21999Y1525715I-266J298D01*
G01Y1529399D01*
X24600Y1532000D01*
X24902D01*
X32420Y1524481D01*
G02X32117Y1523799I-283J-283D01*
G03X29697Y1521498I-118J-2299D01*
G02X29297Y1521098I-400J0D01*
G01X28819D01*
G37*
G36*
G01X62159Y423898D02*
X51200Y434856D01*
Y446476D01*
G02X51883Y446759I400J0D01*
G01X71697Y426945D01*
X71490Y426738D01*
X71398Y426746D01*
G03X71048Y426760I-343J-4187D01*
G01X66748D01*
G03X62816Y424039I0J-4201D01*
G02X62159Y423898I-374J142D01*
G37*
G36*
G01X99590Y407756D02*
X78475Y428870D01*
G02X78712Y429550I283J283D01*
G03X73330Y434932I-562J4820D01*
G02X72650Y434695I-397J46D01*
G01X56150Y451195D01*
Y452209D01*
G02X56833Y452492I400J0D01*
G01X68752Y440574D01*
X82134D01*
X89934Y432774D01*
X129758D01*
X139211Y423321D01*
X139204Y423229D01*
G03X142774Y424967I2295J-179D01*
G02Y425633I221J333D01*
G03X142995Y429299I-1275J1917D01*
G01X142926Y429359D01*
Y432959D01*
X153702Y443736D01*
Y445716D01*
X153935Y445948D01*
X155921D01*
X156615Y446643D01*
G02X157298Y446366I283J-283D01*
G03X161776Y447150I2302J33D01*
G01X161735Y447269D01*
X214426Y499959D01*
Y512045D01*
X217354Y514974D01*
X218191D01*
X218251Y514904D01*
G03Y517896I1749J1496D01*
G01X218191Y517826D01*
X216172D01*
X211572Y513227D01*
Y501141D01*
X202009Y491578D01*
G02X201326Y491861I-283J283D01*
G01Y552241D01*
X201396Y552301D01*
G03X198404I-1496J1749D01*
G01X198474Y552241D01*
Y492542D01*
X197603Y491671D01*
G02X197011Y491700I-283J283D01*
G03X194052Y492474I-2012J-1650D01*
G02X193546Y492674I-145J372D01*
G03X189995Y493857I-2347J-1124D01*
G02X189727Y493940I-92J177D01*
G03X188524Y490701I-2028J-1090D01*
G02X188781Y490588I71J-187D01*
G03X189008Y490147I2416J965D01*
G02X188914Y489614I-337J-215D01*
G03X187919Y487211I1585J-2064D01*
G02X187593Y486766I-397J-51D01*
G03X186251Y485996I408J-2265D01*
G01X186191Y485926D01*
X176791D01*
X173988Y488730D01*
G02X174008Y489315I282J283D01*
G03X173995Y492802I-1509J1738D01*
G01X173926Y492862D01*
Y495879D01*
X179006Y500959D01*
Y658379D01*
X279990Y759363D01*
G02X280673Y759080I283J-283D01*
G01X280672Y746859D01*
X280603Y746799D01*
G03X283663Y743361I1496J-1749D01*
G02X283935I136J-147D01*
G03X285678Y742755I1564J1689D01*
G01X285770Y742762D01*
X344918Y683613D01*
Y409031D01*
G02X344519Y408631I-400J0D01*
G03X342771Y407825I2J-2302D01*
G01X342711Y407756D01*
X99590D01*
G37*
G36*
G01X72394Y504391D02*
X60531Y492528D01*
G02X59848Y492811I-283J283D01*
G01Y495688D01*
X69234Y505074D01*
X72111D01*
G02X72394Y504391I0J-400D01*
G37*
G36*
G01X59831Y531854D02*
G03X62245Y533628I172J2296D01*
G01X62279Y533776D01*
G02X62399Y533780I123J-1880D01*
G01X70044D01*
G02X71306Y533257I0J-1785D01*
G01X79464Y525099D01*
G03X83455Y523446I3991J3991D01*
G01X87710D01*
G02X87948Y522766I-45J-397D01*
G01X73109Y507926D01*
X68052D01*
X58483Y498358D01*
G02X57801Y498641I-282J283D01*
G01X57800Y502107D01*
X60078Y504385D01*
Y530613D01*
X59519Y531173D01*
G02X59831Y531854I283J282D01*
G37*
G36*
G01X47420Y566673D02*
X52324Y561769D01*
Y560818D01*
G02X51610Y560571I-400J0D01*
G03X49566Y561440I-1811J-1421D01*
G02X49126Y561838I-40J398D01*
G01Y562991D01*
X46126Y565991D01*
G02X46409Y566673I283J282D01*
G01X47420D01*
G37*
G36*
G01X59384Y1043784D02*
G02X58701Y1044067I-283J283D01*
G01X58702Y1156222D01*
X61928Y1159449D01*
Y1159451D01*
X105891Y1203414D01*
X105983Y1203407D01*
G03X103867Y1205523I179J2295D01*
G01X103874Y1205431D01*
X59076Y1160633D01*
Y1160631D01*
X57483Y1159039D01*
G02X56800Y1159322I-283J283D01*
G01Y1409635D01*
X60914Y1413748D01*
G02X61597Y1413465I283J-283D01*
G01X61596Y1371886D01*
X75470Y1358013D01*
X75463Y1357921D01*
G03X77579Y1360037I2295J-179D01*
G01X77487Y1360030D01*
X64450Y1373068D01*
Y1402619D01*
G02X65015Y1402984I400J1D01*
G03X66748Y1402610I1733J3828D01*
G01X71048D01*
G03Y1411012I0J4201D01*
G01X66748D01*
G03X65015Y1410638I0J-4202D01*
G02X64450Y1411003I-165J364D01*
G01Y1414950D01*
X79252Y1429752D01*
Y1432448D01*
X58500Y1453199D01*
Y1524048D01*
X77690Y1543238D01*
G02X78279Y1543212I283J-283D01*
G03X81705Y1543099I1764J1479D01*
G02X82281Y1543101I289J-277D01*
G03X82270Y1546297I1651J1604D01*
G02X81694Y1546295I-289J277D01*
G03X81522Y1546455I-1652J-1603D01*
G02X81496Y1547044I257J306D01*
G01X90800Y1556347D01*
Y1559264D01*
X90869Y1559324D01*
G03X87950Y1562882I-1496J1749D01*
G02X87391Y1562946I-247J315D01*
G03X84104Y1559751I-1792J-1445D01*
G01X84174Y1559691D01*
Y1557844D01*
G02X83574Y1557497I-400J0D01*
G03X80852Y1557177I-1145J-1997D01*
G02X80577I-138J145D01*
G03X78810Y1557794I-1577J-1677D01*
G02X78376Y1558193I-34J399D01*
G01Y1559598D01*
X78577D01*
X78578D01*
G03X77019Y1563573I22J2302D01*
G02X76486Y1563558I-275J291D01*
G03X73504Y1560051I-1486J-1758D01*
G01X73574Y1559991D01*
Y1552091D01*
X69230Y1547748D01*
G02X68548Y1548031I-282J283D01*
G01Y1560477D01*
X78208Y1570137D01*
G02X78773I282J-283D01*
G03X79908Y1569517I1627J1629D01*
G02X80194Y1568977I-85J-391D01*
G03X82821Y1570366I2135J-860D01*
G02X82535Y1570906I85J391D01*
G03X82029Y1573393I-2135J861D01*
G02Y1573958I283J282D01*
G01X85044Y1576974D01*
X90946D01*
X136342Y1622369D01*
Y1708004D01*
X136458Y1708057D01*
G03X137779Y1709832I-959J2093D01*
G02X138458Y1710060I396J-55D01*
G01X142675Y1705843D01*
G02X144599Y1701199I-4644J-4644D01*
G01X144598Y1678185D01*
G03X146248Y1672964I9085J0D01*
G01X146345Y1672827D01*
X146268Y1672750D01*
X164009Y1655009D01*
G02X165598Y1651172I-3837J-3837D01*
G01Y1597500D01*
G02X163181Y1591663I-8255J-1D01*
G01X136444Y1564926D01*
G03X132747Y1555999I8926J-8926D01*
G01X132748D01*
Y1547322D01*
X132680Y1547262D01*
G03X132098Y1545970I1143J-1292D01*
G01Y1544218D01*
G03X132680Y1542926I1725J0D01*
G01X132748Y1542866D01*
Y1542522D01*
X132680Y1542462D01*
G03X132098Y1541170I1143J-1292D01*
G01Y1539418D01*
G03X132680Y1538126I1725J0D01*
G01X132748Y1538066D01*
Y1537722D01*
X132680Y1537662D01*
G03X132098Y1536370I1143J-1292D01*
G01Y1534618D01*
G03X132680Y1533326I1725J0D01*
G01X132748Y1533266D01*
Y1376426D01*
X132680Y1376366D01*
G03X132098Y1375074I1143J-1292D01*
G01Y1373322D01*
G03X132680Y1372030I1725J0D01*
G01X132748Y1371970D01*
Y1371626D01*
X132680Y1371566D01*
G03X132098Y1370274I1143J-1292D01*
G01Y1368522D01*
G03X132680Y1367230I1725J0D01*
G01X132748Y1367170D01*
Y1352500D01*
G02X131496Y1349478I-4275J1D01*
G01X131009Y1348991D01*
G02X129410Y1348328I-1600J1599D01*
G01X116462D01*
G02X115788Y1348411I1J2788D01*
G03X111804Y1346597I-2288J-257D01*
G02Y1346057I-295J-270D01*
G03X115788Y1344243I1696J-1557D01*
G02X116462Y1344326I675J-2705D01*
G01X129411D01*
G03X133840Y1346160I0J6265D01*
G01X134327Y1346647D01*
G03X136750Y1352499I-5855J5852D01*
G01Y1556000D01*
G02X139275Y1562095I8620J0D01*
G01X166012Y1588832D01*
G03X169602Y1597499I-8669J8668D01*
G01Y1651173D01*
G03X167855Y1656637I-9429J-4D01*
G01X167757Y1656775D01*
X167831Y1656849D01*
X150090Y1674590D01*
G02X148602Y1678184I3594J3593D01*
G01Y1701198D01*
G03X145506Y1708674I-10571J1D01*
G01X127599Y1726581D01*
X127533Y1726515D01*
X127395Y1726618D01*
G03X121078Y1728702I-6320J-8540D01*
G01X117567D01*
G02X117284Y1729384I0J400D01*
G01X123200Y1735300D01*
Y1739098D01*
X183442D01*
G02X184754Y1738554I-1J-1856D01*
G01X187154Y1736154D01*
G02X187672Y1734902I-1252J-1251D01*
G01Y1611754D01*
X187612Y1611695D01*
G03X187098Y1610483I1175J-1213D01*
G01Y1608657D01*
G03X187612Y1607445I1689J1D01*
G01X187672Y1607386D01*
Y1606954D01*
X187612Y1606895D01*
G03X187098Y1605683I1175J-1213D01*
G01Y1603857D01*
G03X187612Y1602645I1689J1D01*
G01X187672Y1602586D01*
Y1336235D01*
X187612Y1336176D01*
G03X187098Y1334964I1175J-1213D01*
G01Y1333138D01*
G03X187612Y1331926I1689J1D01*
G01X187672Y1331867D01*
Y1331435D01*
X187612Y1331376D01*
G03X187098Y1330164I1175J-1213D01*
G01Y1328338D01*
G03X187612Y1327126I1689J1D01*
G01X187672Y1327067D01*
Y1123371D01*
G02X186459Y1120441I-4143J-1D01*
G01X148370Y1082352D01*
G02X146000Y1081370I-2371J2371D01*
G01X145600D01*
Y1081600D01*
X143900Y1083300D01*
X138368D01*
X138332Y1083314D01*
G03X136622I-855J-2137D01*
G01X136586Y1083300D01*
X133426D01*
Y1088491D01*
X130826Y1091091D01*
Y1092166D01*
G02X131415Y1092519I400J0D01*
G03Y1096581I1084J2031D01*
G02X130826Y1096934I-189J353D01*
G01Y1097740D01*
X126287Y1102279D01*
X126294Y1102371D01*
G03X124178Y1100255I-2295J179D01*
G01X124270Y1100262D01*
X127974Y1096558D01*
Y1093403D01*
G02X127326Y1093089I-400J0D01*
G03X124357Y1089573I-1426J-1807D01*
G02X124089Y1088876I-268J-297D01*
G01X119542D01*
G02X119259Y1089559I0J400D01*
G01X120500Y1090800D01*
Y1091292D01*
G02X120878Y1091692I400J1D01*
G03X119000Y1095486I-129J2298D01*
G01X118940Y1095416D01*
X111017D01*
X59384Y1043784D01*
G37*
G36*
G01X67272Y1563237D02*
G02X66589Y1563520I-283J283D01*
G01X66590Y1574472D01*
X74529Y1582412D01*
X74621Y1582405D01*
G03X72505Y1584521I179J2295D01*
G01X72512Y1584429D01*
X65132Y1577050D01*
G02X64450Y1577333I-282J283D01*
G01Y1634903D01*
G02X65015Y1635268I400J1D01*
G03X66748Y1634894I1733J3828D01*
G01X71048D01*
G03Y1643296I0J4201D01*
G01X66748D01*
G03X65015Y1642922I0J-4202D01*
G02X64450Y1643287I-165J364D01*
G01Y1680778D01*
X73564Y1689893D01*
X73685Y1689847D01*
G03X75092Y1694225I815J2153D01*
G02X74911Y1694894I102J387D01*
G01X92991Y1712974D01*
X102378D01*
X102464Y1713060D01*
G02X103147Y1712773I283J-283D01*
G03X107440Y1710771I2602J-24D01*
G02X107724Y1710747I130J-152D01*
G03X108206Y1714118I1775J1466D01*
G02X107926Y1714174I-113J165D01*
G03X107660Y1714515I-2178J-1424D01*
G02X107954Y1715186I294J271D01*
G01X110944D01*
X111004Y1715117D01*
G03X114216Y1718391I1749J1496D01*
G02X114187Y1718983I254J309D01*
G03X111099Y1718835I-1626J1630D01*
G02X111128Y1718243I-254J-309D01*
G03X111004Y1718109I1626J-1629D01*
G01X110944Y1718040D01*
X103409D01*
X101196Y1715826D01*
X91809D01*
X62279Y1686296D01*
G02X61596Y1686579I-283J283D01*
G01Y1692413D01*
G03X61298Y1692800I-400J0D01*
G01X61150Y1692839D01*
Y1696624D01*
Y1696625D01*
Y1700543D01*
X58999Y1702694D01*
Y1716398D01*
X67042D01*
G03X71527Y1717763I-3J8060D01*
G01X71664Y1717854D01*
X71750Y1717768D01*
X77041Y1723059D01*
G02X78292Y1724000I3958J-3960D01*
G01X111900D01*
X112598Y1724698D01*
X121077D01*
G02X125759Y1722759I0J-6621D01*
G01X135409Y1713109D01*
G02X135181Y1712430I-283J-283D01*
G03X133842Y1711748I318J-2280D01*
G02X133562Y1711740I-144J139D01*
G03X132178Y1707755I-1563J-1690D01*
G01X132270Y1707762D01*
X133488Y1706543D01*
Y1702661D01*
G02X133089Y1702261I-400J0D01*
G03Y1697657I0J-2302D01*
G02X133488Y1697257I-1J-400D01*
G01Y1623551D01*
X89764Y1579826D01*
X83862D01*
X67272Y1563237D01*
G37*
G36*
G01X192358Y1175262D02*
G02X191676Y1175545I-282J283D01*
G01Y1734902D01*
G03X189985Y1738985I-5774J0D01*
G01X186594Y1742376D01*
X186474Y1742256D01*
X186342Y1742332D01*
G03X183443Y1743100I-2900J-5090D01*
G01X122306D01*
G03X119801Y1742614I2J-6708D01*
G01X119765Y1742600D01*
X117100D01*
X108702Y1734202D01*
X77501D01*
X77499D01*
G03X73696Y1733416I2J-9603D01*
G01X73658Y1733400D01*
X61500D01*
X58999Y1735901D01*
Y1749674D01*
X69574Y1760248D01*
X94634D01*
X98779Y1756103D01*
G02X98719Y1755488I-283J-283D01*
G03X100178Y1751280I1280J-1913D01*
G01X100270Y1751287D01*
X100433Y1751124D01*
X183859D01*
X324648Y1610335D01*
Y1553265D01*
X323174Y1551791D01*
Y1306077D01*
X192358Y1175262D01*
G37*
G36*
G01X141659Y1789326D02*
X123972Y1807014D01*
X75456D01*
X60808Y1792366D01*
G02X60125Y1792649I-283J283D01*
G01X60126Y1812549D01*
X68674Y1821098D01*
X87663D01*
G02X87946Y1820415I0J-400D01*
G01X86920Y1819388D01*
X86828Y1819395D01*
G03X84347Y1817101I-179J-2295D01*
G02X83947Y1816702I-400J1D01*
G01X82665D01*
X82387Y1816979D01*
X82394Y1817071D01*
G03X80278Y1814955I-2295J179D01*
G01X80370Y1814962D01*
X81483Y1813848D01*
X95809D01*
X99758Y1817798D01*
X154379D01*
G02X154660Y1817113I0J-400D01*
G03X161482I3411J-3451D01*
G02X161763Y1817798I281J285D01*
G01X316102D01*
X333901Y1799998D01*
G02X333802Y1799360I-283J-283D01*
G03X337309Y1795853I1197J-2310D01*
G02X337947Y1795952I355J-184D01*
G01X343890Y1790009D01*
G02X343607Y1789327I-283J-282D01*
G01X168489D01*
G02X168106Y1789841I0J400D01*
G03X164743Y1792490I-2206J659D01*
G02X164151Y1792920I-201J346D01*
G03X163057Y1791410I-2251J480D01*
G02X163649Y1790980I201J-346D01*
G03X163694Y1789841I2251J-481D01*
G02X163311Y1789326I-383J-115D01*
G01X141659D01*
G37*
G36*
G01X66132Y1846066D02*
X59682Y1839615D01*
G02X58999Y1839898I-283J283D01*
G01Y1841664D01*
X64084Y1846749D01*
X65849D01*
G02X66132Y1846066I0J-400D01*
G37*
G36*
G01X75930Y422712D02*
X95858Y402784D01*
G02X95575Y402102I-283J-282D01*
G01X83955D01*
X68382Y417675D01*
G02X68665Y418358I283J283D01*
G01X71048D01*
G03X75248Y422441I0J4202D01*
G02X75930Y422712I400J-12D01*
G37*
G36*
G01X139274Y428142D02*
G02X138605Y427961I-387J102D01*
G01X130940Y435626D01*
X91116D01*
X83316Y443426D01*
X69934D01*
X62990Y450370D01*
G02X62996Y450941I283J283D01*
G03X63681Y452907I-1596J1659D01*
G02X64214Y453336I396J53D01*
G03X66114Y457515I786J2164D01*
G01X66089Y457528D01*
X61498Y462119D01*
Y468313D01*
G02X61988Y468702I400J-1D01*
G03X64716Y470311I515J2244D01*
G01X64757Y470456D01*
X69345D01*
G03X73339Y472110I0J5648D01*
G01X90615Y489386D01*
G02X91298Y489103I283J-283D01*
G01Y485552D01*
X91916Y484934D01*
G02X91633Y484251I-283J-283D01*
G01X91001D01*
X89798Y483048D01*
Y475052D01*
X91501Y473348D01*
X115497D01*
X132497Y490348D01*
X157497D01*
X163200Y496052D01*
Y502048D01*
X158997Y506252D01*
X150365D01*
G02X150082Y506934I0J400D01*
G01X150200Y507052D01*
Y514048D01*
X148497Y515752D01*
X137811D01*
G02X137469Y516359I0J400D01*
G03X133750Y519046I-1970J1190D01*
G01X133690Y518976D01*
X130908D01*
X129333Y517402D01*
X129317D01*
X110392Y498476D01*
X109308D01*
X109248Y498546D01*
G03X108010Y494805I-1749J-1496D01*
G02X108381Y494133I88J-390D01*
G01X106926Y492678D01*
X94872D01*
G02X94589Y493360I0J400D01*
G01X132189Y530960D01*
X134617Y533387D01*
G03X137501Y540350I-6963J6963D01*
G01X137500D01*
Y542749D01*
G02X137900Y543149I400J0D01*
G03Y547753I0J2302D01*
G02X137500Y548153I0J400D01*
G01Y550848D01*
G02X137977Y551240I400J-1D01*
G03X139062Y551290I440J2260D01*
G01X139089Y551298D01*
X140211D01*
X150900Y561988D01*
Y596287D01*
X152564Y597950D01*
G02X153244Y597626I282J-283D01*
G03X157571Y601953I4827J-500D01*
G02X157247Y602633I-41J398D01*
G01X160400Y605787D01*
Y639357D01*
X160702Y639658D01*
Y655032D01*
X156843Y658891D01*
G02X157126Y659574I283J283D01*
G01X164192D01*
Y595260D01*
X157572Y588641D01*
Y576547D01*
G02X157147Y576148I-400J0D01*
G03Y571554I-147J-2297D01*
G02X157572Y571155I25J-399D01*
G01Y556617D01*
G02X157073Y556230I-400J0D01*
G03Y551770I-573J-2230D01*
G02X157572Y551383I99J-387D01*
G01Y511459D01*
X169072Y499959D01*
Y489610D01*
X175609Y483074D01*
X186191D01*
X186251Y483004D01*
G03X187378Y482284I1749J1496D01*
G02X187553Y481616I-108J-385D01*
G01X175384Y469447D01*
G02X174702Y469730I-282J283D01*
G01Y478198D01*
X172148Y480752D01*
X153001D01*
X144383Y472133D01*
G02X143700Y472416I-283J283D01*
G01Y482048D01*
X142497Y483252D01*
X127602D01*
X109602Y465252D01*
X93501D01*
X91798Y463548D01*
Y456552D01*
X91924Y456426D01*
X91935Y456363D01*
G03X91959Y456238I2567J428D01*
G02X91569Y455752I-390J-86D01*
G01X89552D01*
X87298Y453498D01*
Y444502D01*
X89002Y442798D01*
X92783D01*
X92809Y442791D01*
G03X94191I691J2509D01*
G01X94217Y442798D01*
X123202D01*
Y443000D01*
X126000D01*
X138000Y455000D01*
X137334Y455666D01*
G02X137617Y456348I283J282D01*
G01X158001D01*
X158076Y456424D01*
X161396D01*
G02X161679Y455742I0J-400D01*
G01X154739Y448802D01*
X152753D01*
X150850Y446898D01*
Y444918D01*
X140072Y434141D01*
Y429359D01*
X140003Y429299D01*
G03X139274Y428142I1495J-1750D01*
G37*
G36*
G01X65284Y486103D02*
X78820D01*
G03X80962Y486471I-1J6426D01*
G02X81378Y485811I133J-377D01*
G01X70508Y474941D01*
G02X69343Y474458I-1165J1165D01*
G01X64803D01*
X64781Y474634D01*
G03X61987Y476591I-2284J-288D01*
G02X61498Y476981I-89J390D01*
G01Y483740D01*
G02X62058Y484107I400J0D01*
G03X65262Y485929I920J2110D01*
G01X65284Y486103D01*
G37*
G36*
G01X177991Y829709D02*
X167000Y840700D01*
X147831D01*
X145408Y843124D01*
X100946D01*
X100904Y843266D01*
G03X97204Y844350I-2204J-666D01*
G02X96592Y844464I-260J304D01*
G03X96240Y844674I-352J-190D01*
G01X86500D01*
X86501Y924180D01*
G03X85230Y928423I-7719J-1D01*
G01X85141Y928559D01*
X85231Y928649D01*
X82740Y931140D01*
G02X82001Y932923I1783J1784D01*
G01X82002Y939900D01*
G02X82582Y941302I1983J0D01*
G01X85781Y944501D01*
X85645Y944637D01*
X85713Y944768D01*
G03X86302Y947162I-4573J2395D01*
G01Y971500D01*
G02X87528Y974461I4187J1D01*
G01X98574Y985507D01*
X98484Y985597D01*
X98574Y985733D01*
G03X99852Y989993I-6469J4262D01*
G01Y1054127D01*
G02X100590Y1055910I2521J1D01*
G01X121591Y1076911D01*
G02X122251Y1076760I283J-283D01*
G03X126213Y1076075I2172J763D01*
G02X126924Y1075823I311J-252D01*
G01Y1066550D01*
X130525Y1062948D01*
X162089D01*
X197426Y1098286D01*
Y1171626D01*
X326600Y1300800D01*
X334048D01*
Y1096110D01*
X174364Y936426D01*
X172909D01*
X172849Y936496D01*
G03X172331Y936945I-1750J-1495D01*
G02X172316Y937611I214J338D01*
G03X173210Y940146I-1316J1889D01*
G01X173202Y940173D01*
Y943788D01*
X175652Y946238D01*
Y950738D01*
X170738Y955652D01*
X169009D01*
X165259Y959402D01*
X155195D01*
G02X154796Y959831I0J400D01*
G03X150751Y961496I-2296J169D01*
G01X150691Y961426D01*
X149640D01*
X107050Y1004016D01*
Y1051533D01*
X112234Y1056717D01*
X112335Y1056701D01*
G03X114552Y1057608I364J2273D01*
G02X115274Y1057370I322J-238D01*
G01Y1014026D01*
X169176Y960124D01*
X169868D01*
X169922Y960010D01*
G03X170865Y963003I2078J990D01*
G01X170819Y962976D01*
X170358D01*
X156378Y976957D01*
G02Y977522I283J283D01*
G03X153122Y980778I-1629J1627D01*
G02X152557I-283J283D01*
G01X118126Y1015208D01*
Y1061691D01*
X118196Y1061751D01*
G03X115204I-1496J1749D01*
G01X115274Y1061691D01*
Y1060578D01*
G02X114552Y1060340I-400J0D01*
G03X110397Y1058995I-1853J-1366D01*
G01X110396Y1058914D01*
X104198Y1052715D01*
Y1002834D01*
X114671Y992360D01*
G02X114388Y991678I-283J-282D01*
G01X111536D01*
X109584Y993630D01*
X109569Y993672D01*
G03X105190Y992254I-2169J-772D01*
G01X105198Y992227D01*
Y991788D01*
X108041Y988946D01*
G02X107690Y988269I-283J-283D01*
G03X106194Y983981I-390J-2269D01*
G01X106219Y983967D01*
X107024Y983162D01*
X113250D01*
X142728Y953684D01*
G02X142445Y953001I-283J-283D01*
G01X142112D01*
X112412Y982702D01*
X105273D01*
X105246Y982710D01*
G03Y978290I-646J-2210D01*
G01X105273Y978298D01*
X110588D01*
X140288Y948598D01*
X153591D01*
X156648Y945542D01*
X156661Y945488D01*
G03X159815Y948642I2525J629D01*
G01X159761Y948655D01*
X157301Y951116D01*
G02X157584Y951799I283J283D01*
G01X162109D01*
X167609Y946298D01*
X168519D01*
G02X168802Y945616I0J-400D01*
G01X168798Y945612D01*
Y940173D01*
X168790Y940146D01*
G03X169769Y937555I2210J-646D01*
G02X169784Y936889I-214J-338D01*
G03X169931Y933017I1316J-1889D01*
G02X170003Y932745I-101J-172D01*
G03X173871Y932941I1997J-1145D01*
G02X174197Y933574I325J233D01*
G01X175546D01*
X308789Y1066816D01*
G02X309472Y1066533I283J-283D01*
G01Y1014475D01*
X222531Y927535D01*
G02X221882Y927657I-283J283D01*
G03X217549Y928336I-2383J-1044D01*
G02X216949I-300J264D01*
G03Y924890I-1950J-1723D01*
G02X217549I300J-264D01*
G03X218455Y924230I1949J1724D01*
G02X218577Y923581I-161J-366D01*
G01X199372Y904376D01*
Y898409D01*
X199303Y898349D01*
G03X202295I1496J-1749D01*
G01X202226Y898409D01*
Y903194D01*
X310439Y1011407D01*
G02X311122Y1011124I283J-283D01*
G01Y962839D01*
X177991Y829709D01*
G37*
G36*
G01X72747Y1771784D02*
X74774Y1773812D01*
X297703D01*
X299730Y1771784D01*
G02X299447Y1771102I-283J-282D01*
G01X73030D01*
G02X72747Y1771784I0J400D01*
G37*
G36*
G01X76730Y1784302D02*
X71183Y1789849D01*
X71072Y1789821D01*
G02X68872Y1790421I-574J2229D01*
G03X68307I-282J-283D01*
G01X64275Y1786389D01*
Y1772993D01*
X62458Y1771177D01*
G02X61776Y1771460I-282J283D01*
G01Y1789298D01*
X72651Y1800174D01*
G02X73332Y1799939I284J-282D01*
G03X81963Y1803513I4818J573D01*
G02X82277Y1804160I314J247D01*
G01X122790D01*
X138591Y1788359D01*
G02X138308Y1787676I-283J-283D01*
G01X119390D01*
X108290Y1798776D01*
X87408D01*
X87348Y1798846D01*
G03Y1795854I-1749J-1496D01*
G01X87408Y1795924D01*
X107108D01*
X116222Y1786809D01*
G02X115939Y1786127I-283J-282D01*
G01X103208D01*
X103148Y1786196D01*
G03X99097Y1784701I-1749J-1496D01*
G02X98697Y1784302I-400J1D01*
G01X76730D01*
G37*
G36*
G01X86898Y394476D02*
X84459Y396916D01*
G02X84742Y397598I283J282D01*
G01X346064D01*
G02X346347Y396916I0J-400D01*
G01X343908Y394476D01*
X86898D01*
G37*
G36*
G01X89500Y444000D02*
X88500Y445000D01*
Y453000D01*
X90050Y454550D01*
X93192D01*
X93237Y454525D01*
G03X95763I1263J2275D01*
G01X95808Y454550D01*
X99033D01*
X99083Y454518D01*
G03X101917I1417J2182D01*
G01X101967Y454550D01*
X114999D01*
X128499Y468050D01*
X141999D01*
X153499Y479550D01*
X171650D01*
X173500Y477700D01*
Y467562D01*
X163564Y457626D01*
X157574D01*
X157499Y457550D01*
X135500D01*
X131819Y453869D01*
X131679Y453988D01*
G03X128012Y450321I-1679J-1988D01*
G01X128131Y450181D01*
X121950Y444000D01*
X89500D01*
G37*
G36*
G01X93499Y456550D02*
X92999Y457050D01*
Y463050D01*
X93999Y464050D01*
X110100D01*
X128100Y482050D01*
X137892D01*
X137937Y482025D01*
G03X140463I1263J2275D01*
G01X140508Y482050D01*
X141999D01*
X142499Y481550D01*
Y470249D01*
X141800Y469550D01*
X127499D01*
X114499Y456550D01*
X93499D01*
G37*
G36*
G01X91499Y483050D02*
X112999D01*
X130999Y501050D01*
X144999D01*
X148999Y505050D01*
X158499D01*
X161999Y501550D01*
Y496550D01*
X156999Y491550D01*
X131999D01*
X114999Y474550D01*
X91999D01*
X90999Y475550D01*
Y482550D01*
X91499Y483050D01*
G37*
G36*
G01X93499Y485050D02*
X92499Y486050D01*
Y490199D01*
X93776Y491476D01*
X107424D01*
X111572Y495624D01*
X111574D01*
X130499Y514548D01*
X130515D01*
X130516Y514550D01*
X147999D01*
X148999Y513550D01*
Y507550D01*
X144499Y503050D01*
X128999D01*
X110999Y485050D01*
X93499D01*
G37*
G36*
G01X835155Y1558052D02*
X552933Y1840274D01*
X157450D01*
X156272Y1841452D01*
X100421D01*
G02X100062Y1842029I-1J400D01*
G03X100301Y1843049I-2063J1021D01*
G02X100701Y1843448I400J-1D01*
G01X132245D01*
X133670Y1842024D01*
X552568D01*
X835857Y1558734D01*
G02X835574Y1558052I-283J-282D01*
G01X835155D01*
G37*
G36*
G01X116283Y1077265D02*
G02X115600Y1077548I-283J283D01*
G01Y1082915D01*
X117059Y1084374D01*
X125700D01*
X126924Y1083150D01*
Y1082877D01*
G02X126213Y1082625I-400J0D01*
G03X122131Y1081394I-1790J-1448D01*
G03X119020Y1080002I268J-4772D01*
G01X116283Y1077265D01*
G37*
G36*
G01X141793Y1855274D02*
X141476Y1855591D01*
G02X141759Y1856274I283J283D01*
G01X142740D01*
X146712Y1860245D01*
X148211D01*
G02X148494Y1859563I0J-400D01*
G01X144205Y1855274D01*
X141793D01*
G37*
G36*
G01X139574Y1859818D02*
G03X140301Y1861499I-1575J1679D01*
G02X140701Y1861900I400J1D01*
G01X143365D01*
G02X143648Y1861217I0J-400D01*
G01X141558Y1859126D01*
X139848D01*
G02X139574Y1859818I0J400D01*
G37*
G36*
G01X151201Y1079521D02*
X190281Y1118601D01*
X190195Y1118687D01*
X190287Y1118823D01*
G03X190529Y1119204I-6753J4557D01*
G02X191272Y1119000I343J-205D01*
G01Y1100835D01*
X159539Y1069102D01*
X145600D01*
Y1077368D01*
X146001D01*
G03X151201Y1079521I0J7356D01*
G37*
G36*
G01X343314Y1777798D02*
X380930Y1740183D01*
G02X380647Y1739500I-283J-283D01*
G01X369400D01*
Y1743166D01*
X350787Y1761779D01*
X350794Y1761871D01*
G03X348678Y1759755I-2295J179D01*
G01X348770Y1759762D01*
X366548Y1741984D01*
Y1738748D01*
X361200Y1733400D01*
Y1727966D01*
G02X360517Y1727683I-400J0D01*
G01X356300Y1731900D01*
X349600D01*
X346625Y1728925D01*
X298885Y1776664D01*
X149642D01*
G02X149242Y1777064I0J400D01*
G03X149161Y1777305I-400J0D01*
G02X148732Y1779090I1838J1386D01*
G01X198860D01*
X200151Y1777798D01*
X343314D01*
G37*
G36*
G01X186600Y805314D02*
Y811448D01*
X192221D01*
X200991Y820218D01*
G02X201673Y819935I282J-283D01*
G01X201674Y817291D01*
X189697Y805314D01*
X186600D01*
G37*
G36*
G01Y793852D02*
Y796624D01*
X318690D01*
X318750Y796554D01*
G03X320690Y795756I1749J1496D01*
G02X321006Y795075I33J-398D01*
G01X319783Y793852D01*
X186600D01*
G37*
G36*
G01X322793Y797859D02*
G03X318750Y799546I-2294J191D01*
G01X318690Y799476D01*
X186600D01*
Y802462D01*
X190879D01*
X204526Y816109D01*
Y821420D01*
X340576Y957469D01*
Y960000D01*
X343000D01*
X344072Y958928D01*
Y815560D01*
X331691Y803179D01*
G02X331126I-283J283D01*
G03X327204Y801371I-1627J-1629D01*
G01X327211Y801279D01*
X323474Y797543D01*
G02X322793Y797859I-283J283D01*
G37*
G36*
G01X336072Y959335D02*
X191039Y814302D01*
X186600D01*
Y821100D01*
X180009Y827691D01*
X313974Y961657D01*
Y1065175D01*
X316313Y1067514D01*
X339849Y1091051D01*
X340200Y1090700D01*
X342248D01*
Y1061316D01*
X336072Y1055141D01*
Y959335D01*
G37*
G36*
G01X325617Y1627491D02*
X188843Y1764266D01*
G02X189126Y1764948I283J282D01*
G01X299564D01*
X341106Y1723406D01*
X326300Y1708600D01*
Y1627774D01*
G02X325617Y1627491I-400J0D01*
G37*
G36*
G01X287138Y337799D02*
G03X284820Y340945I-2139J851D01*
G01X284728Y340938D01*
X246451Y379216D01*
G02X246734Y379898I283J282D01*
G01X348083D01*
G02X348366Y379216I0J-400D01*
G01X306402Y337252D01*
X287510D01*
G02X287138Y337799I0J400D01*
G37*
G36*
G01X268672Y1872686D02*
X281608Y1885623D01*
Y1892735D01*
X331352Y1942479D01*
X331444Y1942472D01*
G03X331621Y1942465I179J2295D01*
G02X332020Y1942065I-1J-400D01*
G01Y1933508D01*
X270516Y1872003D01*
X268955D01*
G02X268672Y1872686I0J400D01*
G37*
G36*
G01X357230Y775549D02*
X328020Y746338D01*
X327928Y746345D01*
G03X326227Y742323I-179J-2295D01*
G02X326247Y742043I-132J-150D01*
G03X330294Y740729I1752J-1493D01*
G01X330287Y740821D01*
X359848Y770381D01*
G02X360530Y770098I282J-283D01*
G01Y727099D01*
X350770Y717338D01*
X350678Y717345D01*
G03X352794Y715229I-179J-2295D01*
G01X352787Y715321D01*
X360517Y723051D01*
G02X361200Y722768I283J-283D01*
G01Y420111D01*
X348454Y407366D01*
G02X347772Y407649I-282J283D01*
G01Y684795D01*
X287787Y744779D01*
X287794Y744871D01*
G03X283935Y746739I-2295J179D01*
G02X283663I-136J147D01*
G03X283595Y746799I-1557J-1696D01*
G01X283526Y746859D01*
Y760565D01*
X288393Y765432D01*
G02X288985Y765403I283J-283D01*
G03X289276Y765100I2016J1645D01*
G02Y764500I-264J-300D01*
G03Y760600I1723J-1950D01*
G02Y760000I-264J-300D01*
G03X292733Y756110I1723J-1950D01*
G02X293265I266J-299D01*
G03X296722Y760000I1734J1940D01*
G02Y760600I264J300D01*
G03Y764500I-1723J1950D01*
G02Y765100I264J300D01*
G03X293265Y768990I-1723J1950D01*
G02X292733I-266J299D01*
G03X292646Y769064I-1729J-1944D01*
G02X292617Y769656I254J309D01*
G01X297934Y774974D01*
X326525D01*
X356548Y804996D01*
G02X357230Y804713I282J-283D01*
G01Y775549D01*
G37*
G36*
G01X902735Y1479174D02*
X546821Y1835088D01*
G02X547104Y1835770I283J282D01*
G01X549767D01*
X903418Y1482120D01*
Y1479457D01*
G02X902735Y1479174I-400J0D01*
G37*
G36*
G01X559714Y1845324D02*
X866955Y1538083D01*
G02X866750Y1537408I-283J-283D01*
G03X865547Y1536753I449J-2258D01*
G02X864977Y1536749I-287J278D01*
G01X840374Y1561352D01*
X839609D01*
X556320Y1844641D01*
G02X556603Y1845324I283J283D01*
G01X559714D01*
G37*
G36*
G01X900118Y1159863D02*
X900059Y1122444D01*
X856757Y1079142D01*
X854142D01*
X854082Y1079212D01*
G03Y1076220I-1749J-1496D01*
G01X854142Y1076290D01*
X857939D01*
X901085Y1119435D01*
G02X901767Y1119152I282J-283D01*
G01Y1076220D01*
Y1076090D01*
X901768Y995228D01*
Y993756D01*
G02X901059Y993502I-400J0D01*
G03X897820Y995028I-3239J-2675D01*
G01X893519D01*
G03Y986626I0J-4201D01*
G01X897820D01*
G03X901059Y988152I0J4201D01*
G02X901768Y987898I309J-254D01*
G01Y981727D01*
G02X901313Y981330I-400J0D01*
G03Y976770I-314J-2280D01*
G02X901768Y976373I55J-397D01*
G01Y964659D01*
G02X901239Y964280I-400J0D01*
G03X898750Y963596I-739J-2180D01*
G01X898690Y963526D01*
X898127D01*
X884687Y976966D01*
G02X884691Y977535I283J283D01*
G03X881435Y980791I-1608J1648D01*
G02X880866Y980787I-286J279D01*
G01X780926Y1080728D01*
Y1129242D01*
X780996Y1129302D01*
G03X780731Y1132994I-1497J1748D01*
G02X780662Y1133615I214J338D01*
G01X783996Y1136948D01*
X787475D01*
X787534Y1136852D01*
G03X789665Y1135754I1966J1198D01*
G02X789878Y1135584I15J-200D01*
G03X791988Y1138222I2276J342D01*
G02X791775Y1138392I-15J200D01*
G03X788058Y1139846I-2277J-342D01*
G01X788003Y1139802D01*
X782814D01*
X774691Y1131679D01*
G02X774126I-282J283D01*
G03X773997Y1131798I-1624J-1631D01*
G01X773926Y1131858D01*
Y1159461D01*
X774884Y1160420D01*
Y1162941D01*
G02X775358Y1163334I400J0D01*
G03X777783Y1164169I475J2558D01*
G02X778383I300J-264D01*
G03X780481Y1163294I1950J1723D01*
G02X780880Y1162761I22J-399D01*
G03X781610Y1159942I2453J-869D01*
G02Y1159342I-264J-300D01*
G03X785056I1723J-1950D01*
G02Y1159942I264J300D01*
G03X783185Y1164490I-1723J1950D01*
G02X782786Y1165023I-22J399D01*
G03X778383Y1167615I-2453J869D01*
G02X777783I-300J264D01*
G03X775358Y1168450I-1950J-1723D01*
G02X774884Y1168843I-74J393D01*
G01Y1342418D01*
X866950Y1434484D01*
Y1507623D01*
G02X867633Y1507906I400J0D01*
G01X900118Y1475422D01*
Y1400531D01*
G02X899552Y1400166I-400J-1D01*
G03X897819Y1400540I-1733J-3828D01*
G01X893519D01*
G03Y1392138I0J-4201D01*
G01X897819D01*
G03X899552Y1392512I0J4202D01*
G02X900118Y1392147I166J-364D01*
G01Y1168247D01*
G02X899552Y1167882I-400J-1D01*
G03X897819Y1168256I-1733J-3828D01*
G01X893519D01*
G03Y1159854I0J-4201D01*
G01X897819D01*
G03X899552Y1160228I0J4202D01*
G02X900118Y1159863I166J-364D01*
G37*
G36*
G01X904385Y1485188D02*
X835057Y1554516D01*
G02X835340Y1555198I283J282D01*
G01X837824D01*
X905068Y1487955D01*
Y1485471D01*
G02X904385Y1485188I-400J0D01*
G37*
G36*
G01X909335Y1492391D02*
X868798Y1532928D01*
G02X868802Y1533498I282J283D01*
G03X869457Y1534701I-1603J1652D01*
G02X870132Y1534906I392J-78D01*
G01X910018Y1495020D01*
Y1492674D01*
G02X909335Y1492391I-400J0D01*
G37*
%LPC*%
G75*
G36*
G01X773216Y1973521D02*
G03X773082Y1972988I215J-337D01*
G02X769412Y1973905I-2268J-1275D01*
G03X769546Y1974438I-215J337D01*
G02X773554Y1977647I2268J1274D01*
G03X774087Y1977645I268J298D01*
G02X774074Y1973765I1727J-1946D01*
G03X773541Y1973767I-268J-298D01*
G02X773216Y1973521I-1728J1945D01*
G37*
G36*
G01X785537Y1969763D02*
G03Y1969163I264J-300D01*
G02X782091I-1723J-1950D01*
G03Y1969763I-264J300D01*
G02X781964Y1973542I1723J1950D01*
G03X781991Y1974075I-285J282D01*
G02X785866Y1973879I2025J1633D01*
G03X785839Y1973346I285J-282D01*
G02X785537Y1969763I-2025J-1634D01*
G37*
G36*
G01X344371Y1945560D02*
G03X344315Y1944968I238J-321D01*
G02X341249Y1945258I-1694J-1559D01*
G03X341305Y1945850I-238J321D01*
G02X344371Y1945560I1694J1559D01*
G37*
G36*
G01X100721Y1938595D02*
G03X100188Y1938589I-263J-301D01*
G02X96788Y1942526I-1755J1921D01*
G03X96863Y1943064I-253J310D01*
G02X100936Y1946287I2136J1486D01*
G03X101527Y1946282I298J267D01*
G02X104850Y1942328I1906J-1772D01*
G03X104717Y1941801I218J-335D01*
G02X100721Y1938595I-2284J-1246D01*
G37*
G36*
G01X300765Y1930610D02*
G03X300233I-266J-299D01*
G02X296360Y1931068I-1734J1940D01*
G03X295761Y1931135I-329J-228D01*
G02X296138Y1934532I-1762J1915D01*
G03X296737Y1934465I329J228D01*
G02X300233Y1934490I1762J-1915D01*
G03X300765I266J299D01*
G02X304449Y1934273I1734J-1940D01*
G03X305049I300J264D01*
G02Y1930827I1950J-1723D01*
G03X304449I-300J-264D01*
G02X300765Y1930610I-1950J1723D01*
G37*
G36*
G01X24662Y1923661D02*
G03X25215Y1923647I284J282D01*
G02X25133Y1920322I1550J-1702D01*
G03X24580Y1920336I-284J-282D01*
G02X24662Y1923661I-1550J1702D01*
G37*
G36*
G01X809659Y1912915D02*
G03Y1912315I264J-300D01*
G02X806213I-1723J-1950D01*
G03Y1912915I-264J300D01*
G02X806026Y1916632I1723J1950D01*
G03X806035Y1917165I-294J272D01*
G02X806061Y1920595I1970J1700D01*
G03X806060Y1921128I-299J266D01*
G02X809941Y1921135I1937J1737D01*
G03X809942Y1920602I299J-266D01*
G02X809915Y1917098I-1937J-1737D01*
G03X809906Y1916565I294J-272D01*
G02X809659Y1912915I-1970J-1700D01*
G37*
G36*
G01X793556Y1915433D02*
G03X793557Y1915966I-298J267D01*
G02X793709Y1919582I1944J1729D01*
G03X793708Y1920162I-276J290D01*
G02X797291Y1920164I1790J1888D01*
G03X797292Y1919584I276J-290D01*
G02X797438Y1915959I-1791J-1888D01*
G03X797437Y1915426I298J-267D01*
G02X797448Y1911978I-1944J-1730D01*
G03X797452Y1911446I300J-264D01*
G02X793571Y1911414I-1926J-1750D01*
G03X793567Y1911946I-300J264D01*
G02X793556Y1915433I1926J1750D01*
G37*
G36*
G01X127594Y1907557D02*
G03X126852Y1907552I-370J-152D01*
G02X122788Y1910526I-2419J958D01*
G03X122863Y1911064I-253J310D01*
G02X126936Y1914287I2136J1486D01*
G03X127527Y1914282I298J267D01*
G02X131599Y1911068I1907J-1771D01*
G03X131675Y1910541I333J-221D01*
G02X127594Y1907557I-1676J-1991D01*
G37*
G36*
G01X81265Y1885610D02*
G03X80733I-266J-299D01*
G02X77059Y1889284I-1734J1940D01*
G03Y1889816I-299J266D01*
G02X77276Y1893500I1940J1734D01*
G03Y1894100I-264J300D01*
G02X76833Y1897492I1723J1950D01*
G03X76757Y1898019I-333J221D01*
G02X76788Y1902026I1676J1991D01*
G03X76863Y1902564I-253J310D01*
G02X80936Y1905787I2136J1486D01*
G03X81527Y1905782I298J267D01*
G02X85599Y1902568I1907J-1771D01*
G03X85675Y1902041I333J-221D01*
G02X85696Y1898077I-1676J-1991D01*
G03X85629Y1897544I261J-303D01*
G02X84981Y1893911I-2130J-1494D01*
G03X84914Y1893312I228J-329D01*
G02X84939Y1889816I-1915J-1762D01*
G03Y1889284I299J-266D01*
G02X81265Y1885610I-1940J-1734D01*
G37*
G36*
G01X851925Y1869356D02*
G03X851653Y1869358I-137J-146D01*
G02X851673Y1872736I-1554J1698D01*
G03X851945Y1872734I137J146D01*
G02X851925Y1869356I1554J-1698D01*
G37*
G36*
G01X125186Y1872593D02*
G03X125170Y1872322I139J-144D01*
G02X121799Y1872520I-1777J-1463D01*
G03X121815Y1872791I-139J144D01*
G02X125186Y1872593I1777J1463D01*
G37*
G36*
G01X868561Y1864007D02*
G03Y1863448I286J-279D01*
G02X865267I-1647J-1608D01*
G03Y1864007I-286J280D01*
G02X868561I1647J1608D01*
G37*
G36*
G01X805299Y1824144D02*
G03X805579Y1824111I157J124D01*
G02X805201Y1820864I1421J-1811D01*
G03X804921Y1820897I-157J-124D01*
G02X805299Y1824144I-1421J1811D01*
G37*
G36*
G01X713444Y1823845D02*
G03X713428Y1823573I138J-145D01*
G02X710056Y1823768I-1776J-1464D01*
G03X710072Y1824040I-138J145D01*
G02X713444Y1823845I1776J1464D01*
G37*
G36*
G01X646267Y1817848D02*
G03X646443Y1817255I331J-224D01*
G02X643642Y1816423I-894J-2121D01*
G03X643466Y1817016I-331J224D01*
G02X646267Y1817848I894J2121D01*
G37*
G36*
G01X795489Y1803226D02*
G03X795261Y1803067I-32J-197D01*
G02X793360Y1805774I-2261J433D01*
G03X793588Y1805933I32J197D01*
G02X795489Y1803226I2261J-433D01*
G37*
G36*
G01X884696Y1739970D02*
G03X885255Y1739916I307J256D01*
G02X884904Y1736230I1645J-2016D01*
G03X884345Y1736284I-307J-256D01*
G02X884696Y1739970I-1645J2016D01*
G37*
G36*
G01X979460Y1661707D02*
G03X979724Y1661635I170J105D01*
G02X978840Y1658393I1076J-2035D01*
G03X978576Y1658465I-170J-105D01*
G02X979460Y1661707I-1076J2035D01*
G37*
G36*
G01X983378Y1651669D02*
G03X983460Y1651122I327J-231D01*
G02X980172Y1650633I-1410J-1820D01*
G03X980090Y1651180I-327J231D01*
G02X983378Y1651669I1410J1820D01*
G37*
G36*
G01X752940Y1519266D02*
G03Y1518734I299J-266D01*
G02X749060I-1940J-1734D01*
G03Y1519266I-299J266D01*
G02Y1522734I1940J1734D01*
G03Y1523266I-299J266D01*
G02X752940I1940J1734D01*
G03Y1522734I299J-266D01*
G02Y1519266I-1940J-1734D01*
G37*
G36*
G01X797439Y1507383D02*
G03Y1506717I222J-333D01*
G02X794559I-1440J-2167D01*
G03Y1507383I-222J333D01*
G02X794276Y1511500I1440J2167D01*
G03Y1512100I-264J300D01*
G02Y1516000I1723J1950D01*
G03Y1516600I-264J300D01*
G02X797722I1723J1950D01*
G03Y1516000I264J-300D01*
G02Y1512100I-1723J-1950D01*
G03Y1511500I264J-300D01*
G02X797439Y1507383I-1723J-1950D01*
G37*
G36*
G01X810685Y1506555D02*
G03Y1505889I222J-333D01*
G02X807805I-1440J-2167D01*
G03Y1506555I-222J333D01*
G02X807597Y1510736I1440J2167D01*
G03X807565Y1511379I-253J310D01*
G02X807790Y1515854I1434J2171D01*
G03X807823Y1516543I-186J354D01*
G02X810454Y1516418I1422J2179D01*
G03X810421Y1515729I186J-354D01*
G02X810647Y1511536I-1422J-2179D01*
G03X810679Y1510893I253J-310D01*
G02X810685Y1506555I-1434J-2171D01*
G37*
G36*
G01X974053Y1500177D02*
G03X974073Y1499510I231J-327D01*
G02X971196Y1499423I-1373J-2210D01*
G03X971176Y1500090I-231J327D01*
G02X970826Y1504250I1373J2210D01*
G03Y1504850I-264J300D01*
G02X974272I1723J1950D01*
G03Y1504250I264J-300D01*
G02X974053Y1500177I-1723J-1950D01*
G37*
G36*
G01X961553Y1498177D02*
G03X961573Y1497510I231J-327D01*
G02X958696Y1497423I-1373J-2210D01*
G03X958676Y1498090I-231J327D01*
G02X958326Y1502250I1373J2210D01*
G03Y1502850I-264J300D01*
G02X961772I1723J1950D01*
G03Y1502250I264J-300D01*
G02X961553Y1498177I-1723J-1950D01*
G37*
G36*
G01X952853D02*
G03X952873Y1497510I231J-327D01*
G02X949996Y1497423I-1373J-2210D01*
G03X949976Y1498090I-231J327D01*
G02X949626Y1502250I1373J2210D01*
G03Y1502850I-264J300D01*
G02X953072I1723J1950D01*
G03Y1502250I264J-300D01*
G02X952853Y1498177I-1723J-1950D01*
G37*
G36*
G01X850696Y1464683D02*
G03X850424Y1464688I-139J-144D01*
G02X850480Y1468065I-1536J1714D01*
G03X850752Y1468060I139J144D01*
G02X850696Y1464683I1536J-1714D01*
G37*
G36*
G01X973423Y1450850D02*
G03Y1450250I264J-300D01*
G02X969977I-1723J-1950D01*
G03Y1450850I-264J300D01*
G02X970260Y1454967I1723J1950D01*
G03Y1455633I-222J333D01*
G02X969977Y1459750I1440J2167D01*
G03Y1460350I-264J300D01*
G02X970316Y1464504I1723J1950D01*
G03X970290Y1465197I-212J339D01*
G02X972884Y1465296I1211J2303D01*
G03X972910Y1464603I212J-339D01*
G02X973423Y1460350I-1210J-2303D01*
G03Y1459750I264J-300D01*
G02X973140Y1455633I-1723J-1950D01*
G03Y1454967I222J-333D01*
G02X973423Y1450850I-1440J-2167D01*
G37*
G36*
G01X954223D02*
G03Y1450250I264J-300D01*
G02X950777I-1723J-1950D01*
G03Y1450850I-264J300D01*
G02X951060Y1454967I1723J1950D01*
G03Y1455633I-222J333D01*
G02X950777Y1459750I1440J2167D01*
G03Y1460350I-264J300D01*
G02X951116Y1464504I1723J1950D01*
G03X951090Y1465197I-212J339D01*
G02X953684Y1465296I1211J2303D01*
G03X953710Y1464603I212J-339D01*
G02X954223Y1460350I-1210J-2303D01*
G03Y1459750I264J-300D01*
G02X953940Y1455633I-1723J-1950D01*
G03Y1454967I222J-333D01*
G02X954223Y1450850I-1440J-2167D01*
G37*
G36*
G01X963923Y1449850D02*
G03Y1449250I264J-300D01*
G02X960477I-1723J-1950D01*
G03Y1449850I-264J300D01*
G02X960760Y1453967I1723J1950D01*
G03Y1454633I-222J333D01*
G02X960477Y1458750I1440J2167D01*
G03Y1459350I-264J300D01*
G02X960816Y1463504I1723J1950D01*
G03X960790Y1464197I-212J339D01*
G02X963384Y1464296I1211J2303D01*
G03X963410Y1463603I212J-339D01*
G02X963923Y1459350I-1210J-2303D01*
G03Y1458750I264J-300D01*
G02X963640Y1454633I-1723J-1950D01*
G03Y1453967I222J-333D01*
G02X963923Y1449850I-1440J-2167D01*
G37*
G36*
G01X973723Y1440050D02*
G03Y1439450I264J-300D01*
G02X970277I-1723J-1950D01*
G03Y1440050I-264J300D01*
G02X973723I1723J1950D01*
G37*
G36*
G01X954523D02*
G03Y1439450I264J-300D01*
G02X951077I-1723J-1950D01*
G03Y1440050I-264J300D01*
G02X954523I1723J1950D01*
G37*
G36*
G01X964223Y1439050D02*
G03Y1438450I264J-300D01*
G02X960777I-1723J-1950D01*
G03Y1439050I-264J300D01*
G02X964223I1723J1950D01*
G37*
G36*
G01X747737Y714135D02*
G03X747138Y714068I-270J-295D01*
G02X743517Y717689I-2139J1482D01*
G03X743584Y718288I-228J329D01*
G02X747449Y721773I1915J1762D01*
G03X748049I300J264D01*
G02X751696Y718077I1949J-1724D01*
G03X751629Y717544I261J-303D01*
G02X747737Y714135I-2130J-1494D01*
G37*
G36*
G01X796054Y700903D02*
G03Y700303I264J-300D01*
G02X792608I-1723J-1950D01*
G03Y700903I-264J300D01*
G02Y704803I1723J1950D01*
G03Y705403I-264J300D01*
G02Y709303I1723J1950D01*
G03Y709903I-264J300D01*
G02X796054I1723J1950D01*
G03Y709303I264J-300D01*
G02Y705403I-1723J-1950D01*
G03Y704803I264J-300D01*
G02Y700903I-1723J-1950D01*
G37*
G36*
G01X808462Y699826D02*
G03X808485Y699186I251J-311D01*
G02X805368Y699077I-1486J-2136D01*
G03X805345Y699717I-251J311D01*
G02X805391Y704020I1486J2136D01*
G03Y704686I-222J333D01*
G02Y709020I1440J2167D01*
G03Y709686I-222J333D01*
G02X808271I1440J2167D01*
G03Y709020I222J-333D01*
G02Y704686I-1440J-2167D01*
G03Y704020I222J-333D01*
G02X808462Y699826I-1440J-2167D01*
G37*
G36*
G01X849639Y653715D02*
G03X849367Y653710I-133J-149D01*
G02X849305Y657087I-1595J1660D01*
G03X849577Y657092I133J149D01*
G02X849639Y653715I1595J-1660D01*
G37*
G36*
G01X880243Y647740D02*
G03Y647181I286J-279D01*
G02X876949I-1647J-1608D01*
G03Y647740I-286J279D01*
G02X880243I1647J1608D01*
G37*
G36*
G01X552537Y617750D02*
G03X552563Y618311I-271J294D01*
G02X552776Y622000I1936J1739D01*
G03Y622600I-264J300D01*
G02X556319Y626409I1723J1950D01*
G03X556879I280J286D01*
G02X560517Y622689I1819J-1860D01*
G03X560518Y622115I279J-287D01*
G02X560475Y618334I-1809J-1870D01*
G03X560447Y617775I271J-294D01*
G02X556774Y614102I-1948J-1725D01*
G03X556215Y614074I-265J-299D01*
G02X552537Y617750I-1911J1766D01*
G37*
G36*
G01X886331Y557476D02*
X901190D01*
X901250Y557546D01*
G02Y554554I1749J-1496D01*
G01X901190Y554624D01*
X885149D01*
X779448Y660325D01*
Y701022D01*
X780572Y702147D01*
Y723741D01*
X780503Y723801D01*
G02X783495I1496J1749D01*
G01X783426Y723741D01*
Y700965D01*
X782300Y699840D01*
Y661507D01*
X877469Y566338D01*
G03X878077Y566389I282J283D01*
G02X881289Y563177I1873J-1339D01*
G03X881238Y562569I232J-326D01*
G01X886331Y557476D01*
G37*
G36*
G01X556229Y328457D02*
G03X556220Y329051I-272J293D01*
G02X556083Y332840I1713J1959D01*
G03X556105Y333378I-284J281D01*
G02X559949Y333220I1994J1672D01*
G03X559927Y332682I284J-281D01*
G02X559703Y329103I-1994J-1672D01*
G03X559712Y328509I272J-293D01*
G02X559939Y324816I-1713J-1959D01*
G03Y324284I299J-266D01*
G02X556059I-1940J-1734D01*
G03Y324816I-299J266D01*
G02X556229Y328457I1940J1734D01*
G37*
G36*
G01X754057Y312384D02*
G03X753530Y312308I-221J-333D01*
G02X749607Y315727I-1991J1676D01*
G03X749602Y316269I-297J268D01*
G02X752633Y320392I1897J1781D01*
G03X753146Y320538I175J360D01*
G02X757083Y317211I2200J-1390D01*
G03X757103Y316599I267J-298D01*
G02X754057Y312384I-1603J-2050D01*
G37*
G36*
G01X281721Y297664D02*
G03Y297064I264J-300D01*
G02X278275I-1723J-1950D01*
G03Y297664I-264J300D01*
G02Y301564I1723J1950D01*
G03Y302164I-264J300D01*
G02Y306064I1723J1950D01*
G03Y306664I-264J300D01*
G02X281721I1723J1950D01*
G03Y306064I264J-300D01*
G02Y302164I-1723J-1950D01*
G03Y301564I264J-300D01*
G02Y297664I-1723J-1950D01*
G37*
G36*
G01X268938Y297947D02*
G03Y297281I222J-333D01*
G02X266058I-1440J-2167D01*
G03Y297947I-222J333D01*
G02Y302281I1440J2167D01*
G03Y302947I-222J333D01*
G02Y307281I1440J2167D01*
G03Y307947I-222J333D01*
G02X268938I1440J2167D01*
G03Y307281I222J-333D01*
G02Y302947I-1440J-2167D01*
G03Y302281I222J-333D01*
G02Y297947I-1440J-2167D01*
G37*
G36*
G01X849475Y251698D02*
G03X849747Y251693I139J144D01*
G02X849681Y248316I1531J-1719D01*
G03X849409Y248321I-139J-144D01*
G02X849475Y251698I-1531J1719D01*
G37*
G36*
G01X124189Y251243D02*
G03X124221Y250960I156J-126D01*
G02X121007Y250595I-1422J-1810D01*
G03X120975Y250878I-156J126D01*
G02X124189Y251243I1422J1810D01*
G37*
G36*
G01X879725Y242270D02*
G03Y241711I286J-279D01*
G02X876431I-1647J-1608D01*
G03Y242270I-286J280D01*
G02X879725I1647J1608D01*
G37*
G36*
G01X151646Y241896D02*
G03Y241337I286J-280D01*
G02X148352I-1647J-1608D01*
G03Y241896I-286J279D01*
G02X151646I1647J1608D01*
G37*
G36*
G01X831817Y217500D02*
G03X832359Y217386I330J225D01*
G02X831676Y214132I1217J-1954D01*
G03X831134Y214246I-330J-225D01*
G02X831817Y217500I-1217J1954D01*
G37*
G36*
G01X230265Y176110D02*
G03X229733I-266J-299D01*
G02X226276Y180000I-1734J1940D01*
G03Y180600I-264J300D01*
G02Y184500I1723J1950D01*
G03Y185100I-264J300D01*
G02X226365Y189075I1723J1950D01*
G03X226299Y189741I-251J311D01*
G02X229449Y193773I1200J2309D01*
G03X230049I300J264D01*
G02X233439Y189883I1950J-1723D01*
G03Y189217I222J-333D01*
G02X233722Y185100I-1440J-2167D01*
G03Y184500I264J-300D01*
G02Y180600I-1723J-1950D01*
G03Y180000I264J-300D01*
G02X230265Y176110I-1723J-1950D01*
G37*
G36*
G01X869080Y162249D02*
G03X869091Y161657I274J-291D01*
G02X865996Y161599I-1516J-1733D01*
G03X865985Y162191I-274J291D01*
G02X869080Y162249I1516J1733D01*
G37*
G36*
G01X756265Y152610D02*
G03X755733I-266J-299D01*
G02X752276Y156500I-1734J1940D01*
G03Y157100I-264J300D01*
G02X755733Y160990I1723J1950D01*
G03X756265I266J299D01*
G02X759722Y157100I1734J-1940D01*
G03Y156500I264J-300D01*
G02X756265Y152610I-1723J-1950D01*
G37*
G36*
G01X88391Y128814D02*
G03X88346Y128249I259J-305D01*
G02X85107Y128503I-1747J-1499D01*
G03X85152Y129068I-259J305D01*
G02X88391Y128814I1747J1499D01*
G37*
G36*
G01X117387Y128313D02*
G03Y127710I262J-301D01*
G02X114365I-1511J-1737D01*
G03Y128313I-262J302D01*
G02X117387I1511J1737D01*
G37*
G36*
G01X900889Y108905D02*
G03X900609I-140J-143D01*
G02Y112195I-1610J1645D01*
G03X900889I140J143D01*
G02Y108905I1610J-1645D01*
G37*
G36*
G01X892236Y102613D02*
G03X892231Y102022I267J-298D01*
G02X889017Y97950I-1771J-1907D01*
G03X888490Y97874I-221J-333D01*
G02X885059Y101717I-1990J1676D01*
G03Y102383I-222J333D01*
G02X888233Y106490I1440J2167D01*
G03X888765I266J299D01*
G02X892236Y102613I1734J-1940D01*
G37*
G36*
G01X900343Y90059D02*
G03X899759Y89829I-201J-346D01*
G02X898711Y92485I-2204J665D01*
G03X899295Y92715I201J346D01*
G02X900343Y90059I2204J-665D01*
G37*
G36*
G01X281374Y89309D02*
Y92658D01*
X231408Y142624D01*
X116715D01*
X98926Y124834D01*
Y91859D01*
X98995Y91799D01*
G02X96003I-1496J-1749D01*
G01X96072Y91859D01*
Y126016D01*
X115533Y145476D01*
X232590D01*
X284226Y93840D01*
Y89309D01*
X284296Y89249D01*
G02X281304I-1496J-1749D01*
G01X281374Y89309D01*
G37*
G36*
G01X841600Y85137D02*
G03X842199Y84804I400J14D01*
G02X840898Y82463I1300J-2254D01*
G03X840299Y82796I-400J-14D01*
G02X841600Y85137I-1300J2254D01*
G37*
G36*
G01X177295Y77502D02*
G03X176703I-296J-269D01*
G02Y80598I-1704J1548D01*
G03X177295I296J269D01*
G02Y77502I1704J-1548D01*
G37*
G36*
G01X168222Y81600D02*
G03Y81000I264J-300D01*
G02X164776I-1723J-1950D01*
G03Y81600I-264J300D01*
G02X165017Y85689I1723J1950D01*
G03X165084Y86288I-228J329D01*
G02X165276Y90000I1915J1762D01*
G03Y90600I-264J300D01*
G02Y94500I1723J1950D01*
G03Y95100I-264J300D01*
G02X168722I1723J1950D01*
G03Y94500I264J-300D01*
G02Y90600I-1723J-1950D01*
G03Y90000I264J-300D01*
G02X168481Y85911I-1723J-1950D01*
G03X168414Y85312I228J-329D01*
G02X168222Y81600I-1915J-1762D01*
G37*
G36*
G01X159939Y81883D02*
G03Y81217I222J-333D01*
G02X157059I-1440J-2167D01*
G03Y81883I-222J333D01*
G02X156776Y86000I1440J2167D01*
G03Y86600I-264J300D01*
G02X157059Y90717I1723J1950D01*
G03Y91383I-222J333D01*
G02X159939I1440J2167D01*
G03Y90717I222J-333D01*
G02X160222Y86600I-1440J-2167D01*
G03Y86000I264J-300D01*
G02X159939Y81883I-1723J-1950D01*
G37*
G36*
G01X379549Y63827D02*
G03X378949I-300J-264D01*
G02X375276Y67500I-1950J1723D01*
G03Y68100I-264J300D01*
G02X378949Y71773I1723J1950D01*
G03X379549I300J264D01*
G02X383222Y68100I1950J-1723D01*
G03Y67500I264J-300D01*
G02X379549Y63827I-1723J-1950D01*
G37*
G36*
G01X944439Y64383D02*
G03Y63717I222J-333D01*
G02X941559I-1440J-2167D01*
G03Y64383I-222J333D01*
G02X944439I1440J2167D01*
G37*
G36*
G01X906633Y59525D02*
G03X906699Y58859I251J-311D01*
G02X903865Y58575I-1200J-2309D01*
G03X903799Y59241I-251J311D01*
G02X906633Y59525I1200J2309D01*
G37*
G36*
G01X930481Y53911D02*
G03X930414Y53312I228J-329D01*
G02X927017Y53689I-1915J-1762D01*
G03X927084Y54288I-228J329D01*
G02Y57812I1915J1762D01*
G03X927017Y58411I-295J270D01*
G02X927299Y62859I1482J2139D01*
G03X927365Y63525I-185J355D01*
G02X930199Y63241I1634J2025D01*
G03X930133Y62575I185J-355D01*
G02X930414Y58788I-1634J-2025D01*
G03X930481Y58189I295J-270D01*
G02Y53911I-1482J-2139D01*
G37*
G36*
G01X943474Y31916D02*
G03X942808Y31850I-311J-251D01*
G02X942524Y34684I-2309J1200D01*
G03X943190Y34750I311J251D01*
G02X943474Y31916I2309J-1200D01*
G37*
G36*
G01X374549Y13827D02*
G03X373949I-300J-264D01*
G02X369458Y16110I-1950J1723D01*
G03X369192Y16576I-391J86D01*
G02X368276Y21000I807J2474D01*
G03Y21600I-264J300D01*
G02X371722I1723J1950D01*
G03Y21000I264J-300D01*
G02X372540Y18490I-1723J-1950D01*
G03X372806Y18024I391J-86D01*
G02X373949Y17273I-807J-2474D01*
G03X374549I300J264D01*
G02X378449I1950J-1723D01*
G03X379049I300J264D01*
G02X380136Y18005I1950J-1723D01*
G03X380336Y18604I-133J377D01*
G02X383362Y17595I2163J1446D01*
G03X383162Y16996I133J-377D01*
G02X379049Y13827I-2163J-1446D01*
G03X378449I-300J-264D01*
G02X374549I-1950J1723D01*
G37*
G36*
G01X305703Y38502D02*
G02X302514Y41980I-2403J998D01*
G03X302674Y42647I-121J382D01*
G02X305709Y46804I1827J1853D01*
G03X306282Y47057I186J354D01*
G02X307591Y44096I2518J-657D01*
G03X307018Y43843I-186J-354D01*
G02X305286Y42020I-2517J658D01*
G03X305126Y41353I121J-382D01*
G02X305578Y40758I-1824J-1855D01*
G03X306297Y40798I350J194D01*
G02X306422Y38542I2403J-998D01*
G03X305703Y38502I-350J-194D01*
G37*
G36*
G01X226542Y54934D02*
G02X224456I-1043J-2384D01*
G03Y55666I-161J366D01*
G02Y60434I1043J2384D01*
G03Y61166I-161J366D01*
G02X224312Y65865I1043J2384D01*
G03X224332Y66566I-183J356D01*
G02X226666I1167J1984D01*
G03X226686Y65865I203J-345D01*
G02X226542Y61166I-1187J-2315D01*
G03Y60434I161J-366D01*
G02Y55666I-1043J-2384D01*
G03Y54934I161J-366D01*
G37*
G36*
G01X944542Y74934D02*
G02X942456I-1043J-2384D01*
G03Y75666I-161J366D01*
G02X941983Y80165I1043J2384D01*
G03X942009Y80795I-233J325D01*
G02X944989I1490J1755D01*
G03X945015Y80165I259J-305D01*
G02X944542Y75666I-1516J-2115D01*
G03Y74934I161J-366D01*
G37*
G36*
G01X168676Y105290D02*
G02X167422Y103410I1323J-2241D01*
G03X166822Y103810I-396J56D01*
G02X168076Y105690I-1323J2241D01*
G03X168676Y105290I396J-56D01*
G37*
G36*
G01X207516Y106659D02*
G02X205611Y107849I-2017J-1109D01*
G03X205982Y108441I20J400D01*
G02X207887Y107251I2017J1109D01*
G03X207516Y106659I-20J-400D01*
G37*
G36*
G01X928893Y113742D02*
G02X928513Y116784I-1894J1308D01*
G03X929105Y116858I263J302D01*
G02X931745Y117728I1894J-1308D01*
G03X932263Y118201I130J378D01*
G02X935270Y120919I2236J549D01*
G03X935789Y121407I135J377D01*
G02X937228Y119881I2210J643D01*
G03X936709Y119393I-135J-377D01*
G02X933753Y116572I-2210J-643D01*
G03X933235Y116099I-130J-378D01*
G02X929485Y113816I-2236J-549D01*
G03X928893Y113742I-263J-302D01*
G37*
G36*
G01X810813Y294738D02*
G02X807933I-1440J-2167D01*
G03Y295404I-222J333D01*
G02X808162Y299874I1440J2167D01*
G03X808112Y300604I-186J354D01*
G02X807462Y305150I887J2446D01*
G03X807512Y305752I-236J323D01*
G02X810910Y305471I1861J1819D01*
G03X810860Y304869I236J-323D01*
G02X810210Y300747I-1861J-1819D01*
G03X810260Y300017I186J-354D01*
G02X810813Y295404I-887J-2446D01*
G03Y294738I222J-333D01*
G37*
G36*
G01X750629Y1113044D02*
G02X746802Y1113523I-2130J-1494D01*
G03X746869Y1114056I-261J303D01*
G02X747597Y1117742I2130J1494D01*
G03X747731Y1118275I-215J337D01*
G02X752475Y1120350I2268J1275D01*
G03X753208Y1120283I381J123D01*
G02X753023Y1118250I2291J-1233D01*
G03X752290Y1118317I-381J-123D01*
G02X751401Y1117358I-2291J1233D01*
G03X751267Y1116825I215J-337D01*
G02X750696Y1113577I-2268J-1275D01*
G03X750629Y1113044I261J-303D01*
G37*
G36*
G01X960523Y1474450D02*
G02X957077I-1723J-1950D01*
G03Y1475050I-264J300D01*
G02Y1478950I1723J1950D01*
G03Y1479550I-264J300D01*
G02X957456Y1483728I1723J1950D01*
G03X957416Y1484434I-206J342D01*
G02X959844Y1484572I1083J2366D01*
G03X959884Y1483866I206J-342D01*
G02X960523Y1479550I-1084J-2366D01*
G03Y1478950I264J-300D01*
G02Y1475050I-1723J-1950D01*
G03Y1474450I264J-300D01*
G37*
G36*
G01X975223Y1475950D02*
G02X971777I-1723J-1950D01*
G03Y1476550I-264J300D01*
G02Y1480450I1723J1950D01*
G03Y1481050I-264J300D01*
G02X972156Y1485228I1723J1950D01*
G03X972116Y1485934I-206J342D01*
G02X974544Y1486072I1083J2366D01*
G03X974584Y1485366I206J-342D01*
G02X975223Y1481050I-1084J-2366D01*
G03Y1480450I264J-300D01*
G02Y1476550I-1723J-1950D01*
G03Y1475950I264J-300D01*
G37*
G36*
G01X967723Y1476950D02*
G02X964277I-1723J-1950D01*
G03Y1477550I-264J300D01*
G02Y1481450I1723J1950D01*
G03Y1482050I-264J300D01*
G02X964656Y1486228I1723J1950D01*
G03X964616Y1486934I-206J342D01*
G02X967044Y1487072I1083J2366D01*
G03X967084Y1486366I206J-342D01*
G02X967723Y1482050I-1084J-2366D01*
G03Y1481450I264J-300D01*
G02Y1477550I-1723J-1950D01*
G03Y1476950I264J-300D01*
G37*
G36*
G01X564542Y1488934D02*
G02X562456I-1043J-2384D01*
G03Y1489666I-161J366D01*
G02Y1494434I1043J2384D01*
G03Y1495166I-161J366D01*
G02X564542I1043J2384D01*
G03Y1494434I161J-366D01*
G02Y1489666I-1043J-2384D01*
G03Y1488934I161J-366D01*
G37*
G36*
G01X754634Y1764060D02*
G02X751271Y1768029I-1734J1940D01*
G03X751359Y1768555I-250J312D01*
G02X754997Y1772114I2199J1391D01*
G03X755525Y1772190I222J333D01*
G02X755657Y1772335I1989J-1678D01*
G03X755454Y1773006I-286J280D01*
G02X754265Y1773610I545J2544D01*
G03X753733I-266J-299D01*
G02X750370Y1777579I-1734J1940D01*
G03X750458Y1778105I-250J312D01*
G02X751156Y1781622I2199J1391D01*
G03X750926Y1782348I-231J326D01*
G01X637087D01*
X631636Y1787800D01*
Y1805996D01*
X631607Y1806043D01*
G02X636067I2230J1341D01*
G01X636038Y1805996D01*
Y1789624D01*
X638911Y1786752D01*
X758433D01*
X764621Y1792939D01*
X764634Y1792993D01*
G02X767788Y1789839I2525J-629D01*
G01X767734Y1789826D01*
X760257Y1782348D01*
X758956D01*
G03X758645Y1781698I1J-400D01*
G02X758027Y1777880I-2028J-1631D01*
G03X757944Y1777278I216J-337D01*
G02X757860Y1773732I-1945J-1728D01*
G03X758063Y1773061I286J-280D01*
G02X758928Y1768330I-545J-2544D01*
G03X758845Y1767728I216J-337D01*
G02X755166Y1764060I-1946J-1728D01*
G03X754634I-266J-299D01*
G37*
G36*
G01X881185Y1783941D02*
G02X878173Y1783967I-1521J-1728D01*
G03X878179Y1784572I-259J305D01*
G02X878026Y1784720I1522J1727D01*
G01X877690Y1784522D01*
G02X877582Y1784109I-381J-121D01*
G03X876795Y1781801I1782J-1896D01*
G02X876117Y1781455I-395J-63D01*
G01X809432Y1848141D01*
G02X809715Y1848824I283J283D01*
G01X813451D01*
X876763Y1785512D01*
G03X877439Y1785870I283J283D01*
G02X881191Y1784546I2261J430D01*
G03X881185Y1783941I259J-305D01*
G37*
G36*
G01X771383Y1929007D02*
G02Y1931093I-2384J1043D01*
G03X772115I366J161D01*
G02Y1929007I2384J-1043D01*
G03X771383I-366J-161D01*
G37*
G36*
G01X307042Y1966434D02*
G02X304956I-1043J-2384D01*
G03Y1967166I-161J366D01*
G02X307042I1043J2384D01*
G03Y1966434I161J-366D01*
G37*
G36*
G01X139772Y17616D02*
G02X121753Y23225I-9851J100D01*
G03X121422Y23848I-332J223D01*
G01X94516D01*
X94491Y23872D01*
X88528D01*
X83669Y28731D01*
G03X82988Y28480I-283J-283D01*
G02X77772Y33696I-4838J378D01*
G03X78023Y34377I-32J398D01*
G01X70298Y42103D01*
Y76548D01*
X71257Y77507D01*
G03X71116Y77848I-142J141D01*
G01X71001D01*
X69798Y79052D01*
Y86548D01*
X71001Y87752D01*
X88497D01*
X109200Y67048D01*
Y54299D01*
X110598Y52902D01*
X127597D01*
G03X127797Y53648I0J400D01*
G02X130403I1303J2252D01*
G03X130603Y52902I200J-346D01*
G01X145298D01*
X160948Y37252D01*
X186898D01*
G03X187244Y37851I0J400D01*
G02X191171Y41144I2255J1299D01*
G03X191771Y41244I257J306D01*
G02X192361Y41922I2228J-1343D01*
G03X192428Y42475I-251J311D01*
G02X196865Y42968I2071J1575D01*
G03X197332Y42415I364J-166D01*
G02X199723Y37951I667J-2515D01*
G03X199988Y37252I265J-299D01*
G01X252001D01*
X277298Y62548D01*
Y78548D01*
X283001Y84252D01*
X297997D01*
X299200Y83048D01*
Y72916D01*
G03X299883Y72633I400J0D01*
G01X300298Y73048D01*
Y82048D01*
X302501Y84252D01*
X316997D01*
X318200Y83048D01*
Y65552D01*
X311497Y58848D01*
X305997D01*
X289472Y42324D01*
G03X289721Y41643I283J-283D01*
G02X289402Y36450I-222J-2593D01*
G03X289016Y35901I-15J-400D01*
G02X286700Y37528I-2413J-973D01*
G03X287086Y38077I15J400D01*
G02X286906Y38828I2412J975D01*
G03X286225Y39077I-398J-34D01*
G01X264497Y17348D01*
X141001D01*
X140455Y17895D01*
G03X139772Y17616I-283J-283D01*
G37*
G36*
G01X32024Y1510294D02*
G03X31753Y1510282I-129J-152D01*
G02X31603Y1513657I-1638J1618D01*
G03X31874Y1513669I129J152D01*
G02X32024Y1510294I1638J-1618D01*
G37*
G36*
G01X32565Y1495833D02*
G03X32033I-266J-298D01*
G02Y1499267I-1534J1717D01*
G03X32565I266J298D01*
G02Y1495833I1534J-1717D01*
G37*
G36*
G01X32767Y1483524D02*
G03X33044Y1483494I154J128D01*
G02X32697Y1480209I1421J-1811D01*
G03X32420Y1480239I-154J-128D01*
G02X32767Y1483524I-1421J1811D01*
G37*
G36*
G01X32363Y1460981D02*
G03X32080Y1460968I-135J-148D01*
G02X31930Y1464218I-1702J1550D01*
G03X32213Y1464231I135J148D01*
G02X32363Y1460981I1702J-1550D01*
G37*
G36*
G01X30607Y1446691D02*
G03X30335Y1446679I-130J-153D01*
G02X30184Y1450053I-1638J1617D01*
G03X30456Y1450065I130J153D01*
G02X30607Y1446691I1638J-1617D01*
G37*
G36*
G01X32785Y1434821D02*
G03X33001Y1434645I199J23D01*
G02X30920Y1432081I205J-2293D01*
G03X30704Y1432257I-199J-23D01*
G02X32785Y1434821I-205J2293D01*
G37*
G36*
G01X30627Y1413178D02*
G03X30903Y1413171I142J141D01*
G02X30823Y1409840I1548J-1704D01*
G03X30547Y1409847I-142J-141D01*
G02X30627Y1413178I-1548J1704D01*
G37*
G36*
G01X27246Y1370537D02*
G03X27254Y1370004I302J-262D01*
G02X23819Y1369955I-1696J-1557D01*
G03X23811Y1370488I-302J262D01*
G02X27246Y1370537I1696J1557D01*
G37*
G36*
G01X28046Y504133D02*
G03Y503574I286J-280D01*
G02X24752I-1647J-1608D01*
G03Y504133I-286J279D01*
G02X28046I1647J1608D01*
G37*
G36*
G01X28101Y480129D02*
G03X28084Y479858I138J-145D01*
G02X24713Y480073I-1785J-1454D01*
G03X24730Y480344I-138J145D01*
G02X28101Y480129I1785J1454D01*
G37*
G36*
G01X28539Y456990D02*
G03X28554Y456450I302J-262D01*
G02X25159Y456357I-1655J-1600D01*
G03X25144Y456897I-302J262D01*
G02X25202Y460155I1655J1600D01*
G03X25156Y460769I-278J288D01*
G02X24776Y464189I1330J1879D01*
G03X24777Y464722I-298J267D01*
G02X28209Y464709I1722J1528D01*
G03X28208Y464176I298J-267D01*
G02X28083Y460990I-1722J-1528D01*
G03X28129Y460376I278J-288D01*
G02X28539Y456990I-1330J-1879D01*
G37*
G36*
G01X28238Y441132D02*
G03X28229Y440861I142J-140D01*
G02X24853Y440967I-1737J-1511D01*
G03X24862Y441238I-142J140D01*
G02X28238Y441132I1737J1511D01*
G37*
G36*
G01X28093Y654525D02*
G03X28054Y653845I190J-352D01*
G02X25643Y653982I-1317J-1888D01*
G03X25682Y654662I-190J352D01*
G02X28093Y654525I1317J1888D01*
G37*
G36*
G01X28264Y638047D02*
G03Y637507I295J-270D01*
G02X24872I-1696J-1557D01*
G03Y638047I-295J270D01*
G02X28264I1696J1557D01*
G37*
G36*
G01X29195Y622300D02*
G03Y621760I295J-270D01*
G02X25803I-1696J-1557D01*
G03Y622300I-295J270D01*
G02X29195I1696J1557D01*
G37*
G36*
G01X97336Y511711D02*
G03X97064I-136J-147D01*
G02Y515089I-1564J1689D01*
G03X97336I136J147D01*
G02Y511711I1564J-1689D01*
G37*
G36*
G01X52825Y654348D02*
X43499D01*
G02Y660752I0J3202D01*
G01X50173D01*
X159735Y770314D01*
G02X164263Y765786I2264J-2264D01*
G01X52825Y654348D01*
G37*
G36*
G01X77669Y848932D02*
G03X77586Y848673I98J-174D01*
G02X73300Y847023I-2086J-974D01*
G03X72835Y847297I-382J-117D01*
G02X70985Y851395I-473J2253D01*
G01X70996Y851403D01*
X71148Y851555D01*
X70968Y851734D01*
Y977146D01*
X77812Y983989D01*
G03X77577Y984670I-282J284D01*
G02X80971Y993436I573J4818D01*
G03X81511Y993505I233J325D01*
G02X81817Y993648I306J-257D01*
G01X86624D01*
Y994499D01*
X89651Y997526D01*
X90791D01*
X90851Y997596D01*
G02X92673Y993799I1749J-1496D01*
G03X92288Y993355I12J-400D01*
G02X91496Y991351I-2288J-254D01*
G01X91426Y991291D01*
Y990109D01*
X76012Y974695D01*
Y856957D01*
X77472Y855498D01*
Y853047D01*
X77581Y852991D01*
G02X77669Y848932I-1041J-2053D01*
G37*
G36*
G01X53981Y769411D02*
G03X53914Y768812I228J-329D01*
G02X50026Y765353I-1915J-1762D01*
G03X49493Y765420I-303J-261D01*
G02X46059Y769284I-1494J2130D01*
G03Y769816I-299J266D01*
G02X49949Y773273I1940J1734D01*
G03X50549I300J264D01*
G02X53981Y769411I1950J-1723D01*
G37*
G36*
G01X48222Y732500D02*
G02X44360Y729068I-1723J-1950D01*
G03X43761Y729135I-329J-228D01*
G02X40059Y732784I-1763J1914D01*
G03Y733316I-299J266D01*
G02X40276Y737000I1940J1734D01*
G03Y737600I-264J300D01*
G02X39523Y738750I1723J1950D01*
G03X38790Y738817I-381J-123D01*
G02X38975Y740850I-2291J1233D01*
G03X39708Y740783I381J123D01*
G02X44138Y741032I2291J-1233D01*
G03X44737Y740965I329J228D01*
G02X48439Y737316I1763J-1914D01*
G03Y736784I299J-266D01*
G02X48222Y733100I-1940J-1734D01*
G03Y732500I264J-300D01*
G37*
G36*
G01X38299Y716526D02*
G02X36266Y716341I-800J-2476D01*
G03X36199Y717074I-190J352D01*
G02X35956Y721934I800J2476D01*
G03Y722666I-161J366D01*
G02X39308Y726250I1043J2384D01*
G03X39974Y726184I355J185D01*
G02X43949Y726273I2025J-1634D01*
G03X44549I300J264D01*
G02X48666Y725990I1950J-1723D01*
G03X49332I333J222D01*
G02X52981Y722411I2167J-1440D01*
G03X52914Y721812I228J-329D01*
G02X49237Y718135I-1915J-1762D01*
G03X48638Y718068I-270J-295D01*
G02X44332Y718110I-2139J1482D01*
G03X43666I-333J-222D01*
G02X39549Y717827I-2167J1440D01*
G03X38949I-300J-264D01*
G02X38232Y717259I-1949J1724D01*
G03X38299Y716526I190J-352D01*
G37*
G36*
G01X269939Y704383D02*
G03Y703717I222J-333D01*
G02X267059I-1440J-2167D01*
G03Y704383I-222J333D01*
G02Y708717I1440J2167D01*
G03Y709383I-222J333D01*
G02Y713717I1440J2167D01*
G03Y714383I-222J333D01*
G02X269939I1440J2167D01*
G03Y713717I222J-333D01*
G02Y709383I-1440J-2167D01*
G03Y708717I222J-333D01*
G02Y704383I-1440J-2167D01*
G37*
G36*
G01X183678Y558395D02*
X183770Y558388D01*
X281698Y656316D01*
Y698563D01*
G03X281258Y698961I-400J0D01*
G02X279059Y703284I-259J2589D01*
G03Y703816I-299J266D01*
G02X281258Y708139I1940J1734D01*
G03X281698Y708537I40J398D01*
G01Y710715D01*
G03X281182Y711098I-400J0D01*
G02X278757Y715581I-750J2492D01*
G03X278833Y716108I-257J306D01*
G02X281258Y720139I2166J1442D01*
G03X281698Y720537I40J398D01*
G01Y724834D01*
X280210Y726322D01*
X280118Y726315D01*
G02X282234Y728431I-179J2295D01*
G01X282227Y728339D01*
X284550Y726016D01*
Y655134D01*
X185787Y556371D01*
X185794Y556279D01*
G02X183678Y558395I-2295J-179D01*
G37*
G36*
G01X182114Y436757D02*
G03X181534I-290J-276D01*
G02X177874Y440452I-1885J1793D01*
G03X177920Y440985I-273J292D01*
G02X178276Y444500I2079J1565D01*
G03Y445100I-264J300D01*
G02X181733Y448990I1723J1950D01*
G03X182265I266J299D01*
G02X185722Y445100I1734J-1940D01*
G03Y444500I264J-300D01*
G02X185939Y440816I-1723J-1950D01*
G03Y440284I299J-266D01*
G02X182114Y436757I-1940J-1734D01*
G37*
G36*
G01X129939Y423316D02*
G03Y422784I299J-266D01*
G02X126059I-1940J-1734D01*
G03Y423316I-299J266D01*
G02X126276Y427000I1940J1734D01*
G03Y427600I-264J300D01*
G02X129722I1723J1950D01*
G03Y427000I264J-300D01*
G02X129939Y423316I-1723J-1950D01*
G37*
G36*
G01X189222Y533563D02*
G02X185776I-1723J-1950D01*
G03Y534163I-264J300D01*
G02X186918Y538649I1723J1950D01*
G03X187118Y539315I-89J390D01*
G02X187276Y543063I1881J1798D01*
G03Y543663I-264J300D01*
G02X187059Y547347I1723J1950D01*
G03Y547879I-299J266D01*
G02X190949Y551336I1940J1734D01*
G03X191549I300J264D01*
G02X195605Y548085I1950J-1723D01*
G03X195671Y547543I323J-236D01*
G02X195511Y543432I-1672J-1994D01*
G03X195444Y542841I232J-326D01*
G02X191549Y539390I-1945J-1728D01*
G03X190949I-300J-264D01*
G02X189580Y538577I-1949J1723D01*
G03X189380Y537911I89J-390D01*
G02X189222Y534163I-1881J-1798D01*
G03Y533563I264J-300D01*
G37*
G36*
G01X133110Y1731900D02*
G03X132777Y1731307I17J-400D01*
G02X128525Y1731746I-2278J-1257D01*
G03X128192Y1732405I-303J260D01*
G02X130309Y1736200I-192J2595D01*
G03X130975Y1736134I355J185D01*
G02X133110Y1731900I2025J-1634D01*
G37*
G36*
G01X141924Y1731445D02*
G03X142590Y1731318I373J145D01*
G02X142075Y1728605I1909J-1768D01*
G03X141409Y1728732I-373J-145D01*
G02X141924Y1731445I-1909J1768D01*
G37*
G36*
G01X166049Y1724890D02*
G03X165449I-300J-264D01*
G02X162813Y1729123I-1950J1723D01*
G03X163079Y1729656I-106J386D01*
G02X167542Y1732225I2420J958D01*
G03X168208Y1732283I314J248D01*
G02X172755Y1729753I2291J-1233D01*
G03X173021Y1729162I347J-199D01*
G02X170549Y1724890I-522J-2549D01*
G03X169949I-300J-264D01*
G02X166049I-1950J1723D01*
G37*
G36*
G01X169684Y1715526D02*
G03X170350Y1715517I336J217D01*
G02X170314Y1712637I2149J-1467D01*
G03X169648Y1712646I-336J-217D01*
G02X165332Y1712673I-2149J1467D01*
G03X164666I-333J-222D01*
G02Y1715553I-2167J1440D01*
G03X165332I333J222D01*
G02X169684Y1715526I2167J-1440D01*
G37*
G36*
G01X170572Y1688280D02*
Y1692910D01*
X152007Y1711476D01*
X151883Y1711425D01*
G02X153137Y1714403I-884J2125D01*
G01X153152Y1714365D01*
X171752Y1695765D01*
G03X172363Y1695819I283J283D01*
G02X173888Y1692227I1887J-1319D01*
G03X173426Y1691832I-62J-395D01*
G01Y1664059D01*
X173495Y1663999D01*
G02X170503I-1496J-1749D01*
G01X170572Y1664059D01*
Y1679659D01*
G03X170088Y1680050I-400J0D01*
G02X167757Y1683680I-488J2250D01*
G03X167717Y1683959I-160J119D01*
G02X170014Y1687913I1382J1841D01*
G03X170572Y1688280I158J367D01*
G37*
G36*
G01X181869Y1629104D02*
G03X181944Y1628566I328J-228D01*
G02X178163Y1628036I-1645J-2016D01*
G03X178088Y1628574I-328J228D01*
G02X178057Y1632581I1645J2016D01*
G03X178133Y1633108I-257J306D01*
G02X181975Y1632559I2166J1442D01*
G03X181899Y1632032I257J-306D01*
G02X181869Y1629104I-2166J-1442D01*
G37*
G36*
G01X100635Y1534154D02*
G03X100423Y1533983I-14J-199D01*
G02X98309Y1536605I-2279J326D01*
G03X98521Y1536776I14J199D01*
G02X98803Y1537595I2279J-327D01*
G03X98731Y1537866I-174J99D01*
G02X101896Y1538705I1168J1984D01*
G03X101968Y1538434I174J-99D01*
G02X100635Y1534154I-1168J-1984D01*
G37*
G36*
G01X125514Y1467291D02*
G03X125443Y1466671I213J-338D01*
G02X122584Y1467000I-1635J-1621D01*
G03X122655Y1467620I-213J338D01*
G02X125514Y1467291I1635J1621D01*
G37*
G36*
G01X144647Y1458502D02*
G03X144662Y1457965I304J-260D01*
G02X141252Y1457871I-1662J-1592D01*
G03X141237Y1458408I-304J260D01*
G02X144647Y1458502I1662J1592D01*
G37*
G36*
G01X106362Y1443086D02*
G03X106352Y1442448I236J-323D01*
G02X103572Y1442489I-1417J-1814D01*
G03X103582Y1443127I-236J323D01*
G02X106362Y1443086I1417J1814D01*
G37*
G36*
G01X119037Y1428368D02*
G03Y1427809I286J-279D01*
G02X115743I-1647J-1608D01*
G03Y1428368I-286J280D01*
G02X119037I1647J1608D01*
G37*
G36*
G01X98507Y1375860D02*
G03X98541Y1375229I262J-302D01*
G02X95722Y1375077I-1312J-1892D01*
G03X95688Y1375708I-262J302D01*
G02X98507Y1375860I1312J1892D01*
G37*
G36*
G01X182024Y1368175D02*
G03X182098Y1367523I265J-300D01*
G02X179476Y1367225I-1098J-2023D01*
G03X179402Y1367877I-265J300D01*
G02X182024Y1368175I1098J2023D01*
G37*
G36*
G01X123223Y1363404D02*
G03X123595Y1362900I386J-104D01*
G02X121052Y1361182I-95J-2600D01*
G03X120724Y1361715I-376J136D01*
G02X122205Y1365961I275J2285D01*
G03X122812Y1366257I210J341D01*
G02X123895Y1364039I2288J-256D01*
G03X123288Y1363743I-210J-341D01*
G02X123223Y1363404I-2287J263D01*
G37*
G36*
G01X114408Y1359729D02*
G03X114363Y1359461I122J-158D01*
G02X111031Y1360017I-1923J-1265D01*
G03X111076Y1360285I-122J158D01*
G02X114408Y1359729I1923J1265D01*
G37*
G36*
G01X104046Y1346597D02*
G03Y1346057I295J-270D01*
G02X100654I-1696J-1557D01*
G03Y1346597I-295J270D01*
G02X104046I1696J1557D01*
G37*
G36*
G01X88537Y1345027D02*
G03Y1344468I286J-280D01*
G02X85243I-1647J-1608D01*
G03Y1345027I-286J280D01*
G02X88537I1647J1608D01*
G37*
G36*
G01X110875Y1335482D02*
G03Y1334923I286J-280D01*
G02X107581I-1647J-1608D01*
G03Y1335482I-286J279D01*
G02X110875I1647J1608D01*
G37*
G36*
G01X118832Y1326517D02*
G03X118238Y1326505I-292J-274D01*
G02X118174Y1329592I-1739J1508D01*
G03X118768Y1329604I292J274D01*
G02X118832Y1326517I1739J-1508D01*
G37*
G36*
G01X166736Y1310348D02*
X166673D01*
X146017Y1331004D01*
G03X145433Y1330985I-283J-282D01*
G02X142079Y1330866I-1733J1515D01*
G03X141531Y1330881I-282J-284D01*
G02X141621Y1334234I-1531J1719D01*
G03X142169Y1334219I282J284D01*
G02X144583Y1334626I1531J-1719D01*
G03X145101Y1334832I153J369D01*
G02X150288Y1335789I2923J-1307D01*
G01X169325Y1316752D01*
X169388D01*
X177763Y1308377D01*
G02X177920Y1308208I-2266J-2262D01*
G03X178459Y1308147I303J262D01*
G02X181722Y1304100I1540J-2097D01*
G03Y1303500I264J-300D01*
G02X181480Y1299410I-1723J-1950D01*
G03Y1298753I227J-328D01*
G02X181915Y1294852I-1481J-2140D01*
G03Y1294311I294J-270D01*
G02X178049Y1290827I-1916J-1761D01*
G03X177449I-300J-264D01*
G02X173937Y1294631I-1950J1723D01*
G03X173980Y1295233I-240J320D01*
G02X174280Y1299165I1843J1837D01*
G03X174237Y1299837I-237J322D01*
G02X173420Y1303678I1262J2276D01*
G02X173235Y1303849I2079J2435D01*
G01X166736Y1310348D01*
G37*
G36*
G01X146614Y1220320D02*
G03X146034I-290J-276D01*
G02X142209Y1223847I-1885J1793D01*
G03Y1224379I-299J266D01*
G02Y1227847I1940J1734D01*
G03Y1228379I-299J266D01*
G02X146029Y1231912I1940J1735D01*
G03X146606I288J277D01*
G02X150432Y1228386I1879J-1800D01*
G03X150434Y1227853I299J-265D01*
G02X150439Y1224379I-1935J-1740D01*
G03Y1223847I299J-266D01*
G02X146614Y1220320I-1940J-1734D01*
G37*
G36*
G01X125217Y1223508D02*
X125352Y1223421D01*
X177211Y1275279D01*
X177204Y1275371D01*
G02X179320Y1273255I2295J179D01*
G01X179228Y1273262D01*
X126113Y1220146D01*
X125779D01*
X125719Y1220077D01*
G02X125217Y1223508I-1749J1496D01*
G37*
G36*
G01X105113Y1196686D02*
G03X105719Y1196464I384J110D01*
G02X104786Y1193914I1280J-1914D01*
G03X104180Y1194136I-384J-110D01*
G02X105113Y1196686I-1280J1914D01*
G37*
G36*
G01X113265Y1116110D02*
G03X112733I-266J-299D01*
G02X109059Y1119784I-1734J1940D01*
G03Y1120316I-299J266D01*
G02Y1123784I1940J1734D01*
G03Y1124316I-299J266D01*
G02X109276Y1128000I1940J1734D01*
G03Y1128600I-264J300D01*
G02X112930Y1132294I1723J1950D01*
G03X113490Y1132261I297J268D01*
G02X116947Y1128371I1710J-1961D01*
G03X116920Y1127805I268J-296D01*
G02X116939Y1124316I-1921J-1755D01*
G03Y1123784I299J-266D01*
G02Y1120316I-1940J-1734D01*
G03Y1119784I299J-266D01*
G02X113265Y1116110I-1940J-1734D01*
G37*
G36*
G01X107873Y1100042D02*
G03X107320Y1099874I-196J-349D01*
G02X106868Y1099240I-2321J1176D01*
G03X106869Y1098682I287J-278D01*
G02X103421Y1094802I-1863J-1816D01*
G03X102888Y1094760I-243J-317D01*
G02X99276Y1098500I-1889J1790D01*
G03Y1099100I-264J300D01*
G02X102733Y1102990I1723J1950D01*
G03X103265I266J299D01*
G02X106494Y1103180I1734J-1940D01*
G03X107060Y1103291I230J327D01*
G02X107873Y1100042I1939J-1241D01*
G37*
G36*
G01X129306Y1567294D02*
G02X127247Y1566527I-206J-2594D01*
G03X126994Y1567206I-285J280D01*
G02X129053Y1567973I206J2594D01*
G03X129306Y1567294I285J-280D01*
G37*
G36*
G01X97889Y1551664D02*
G02X95618Y1552327I-1689J-1564D01*
G03X95810Y1552986I-101J387D01*
G02X95656Y1555930I1689J1564D01*
G03X95616Y1556209I-160J119D01*
G02X97596Y1560273I1383J1841D01*
G01X97684Y1560250D01*
X155558Y1599926D01*
X158391D01*
X158451Y1599996D01*
G02X159874Y1596221I1749J-1496D01*
G03X159650Y1596065I-28J-198D01*
G02X156827Y1594320I-2250J485D01*
G01X156738Y1594343D01*
X99799Y1554421D01*
X99790Y1554329D01*
G02X98081Y1552323I-2291J221D01*
G03X97889Y1551664I101J-387D01*
G37*
G36*
G01X83883Y1588007D02*
G02X79245Y1590350I-2384J1043D01*
G03X78912Y1590949I-347J199D01*
G02X77265Y1591610I88J2601D01*
G03X76733I-266J-299D01*
G02X73084Y1595312I-1735J1939D01*
G03X73017Y1595911I-295J270D01*
G02X72559Y1599784I1482J2139D01*
G03Y1600316I-299J266D01*
G02X76449Y1603773I1940J1734D01*
G03X77049I300J264D01*
G02X80949I1950J-1723D01*
G03X81549I300J264D01*
G02X85439Y1600316I1950J-1723D01*
G03Y1599784I299J-266D01*
G02Y1596316I-1940J-1734D01*
G03Y1595784I299J-266D01*
G02X83700Y1591456I-1940J-1734D01*
G03X83434Y1590790I32J-399D01*
G02X83883Y1590093I-1935J-1740D01*
G03X84615I366J161D01*
G02X89383I2384J-1043D01*
G03X90115I366J161D01*
G02Y1588007I2384J-1043D01*
G03X89383I-366J-161D01*
G02X84615I-2384J1043D01*
G03X83883I-366J-161D01*
G37*
G36*
G01X86961Y1750609D02*
G03X86949Y1750338I141J-142D01*
G02X83574Y1750484I-1755J-1490D01*
G03X83586Y1750755I-141J142D01*
G02X86961Y1750609I1755J1490D01*
G37*
G36*
G01X111003Y1741807D02*
G03X110988Y1741215I261J-303D01*
G02X107895Y1741293I-1589J-1665D01*
G03X107910Y1741885I-261J303D01*
G02X111003Y1741807I1589J1665D01*
G37*
G36*
G01X197315Y1621743D02*
G03X197328Y1621130I263J-301D01*
G02X193985Y1621057I-1628J-2030D01*
G03X193972Y1621670I-263J301D01*
G02X197315Y1621743I1628J2030D01*
G37*
G36*
G01X308859Y1567965D02*
G03X308268Y1567842I-242J-318D01*
G02X307753Y1571035I-2270J1272D01*
G03X308352Y1571104I269J296D01*
G02X308859Y1567965I1897J-1304D01*
G37*
G36*
G01X292264Y1567174D02*
G03X291732I-266J-299D01*
G02X288275Y1571064I-1734J1940D01*
G03Y1571664I-264J300D01*
G02Y1575564I1723J1950D01*
G03Y1576164I-264J300D01*
G02X291732Y1580054I1723J1950D01*
G03X292264I266J299D01*
G02X295721Y1576164I1734J-1940D01*
G03Y1575564I264J-300D01*
G02Y1571664I-1723J-1950D01*
G03Y1571064I264J-300D01*
G02X292264Y1567174I-1723J-1950D01*
G37*
G36*
G01X281889Y1554405D02*
G03X281609I-140J-143D01*
G02Y1557695I-1610J1645D01*
G03X281889I140J143D01*
G02Y1554405I1610J-1645D01*
G37*
G36*
G01X280712Y1528452D02*
G03X280779Y1527923I329J-227D01*
G02X276930Y1527430I-1704J-1966D01*
G03X276863Y1527959I-329J227D01*
G02X280712Y1528452I1704J1966D01*
G37*
G36*
G01X269119Y1520643D02*
G03Y1520057I273J-293D01*
G02X265579I-1770J-1907D01*
G03Y1520643I-273J293D01*
G02X265688Y1524553I1770J1907D01*
G03Y1525169I-255J308D01*
G02X269010I1661J2003D01*
G03Y1524553I255J-308D01*
G02X269119Y1520643I-1661J-2003D01*
G37*
G36*
G01X281222Y1513100D02*
G03Y1512500I264J-300D01*
G02X277776I-1723J-1950D01*
G03Y1513100I-264J300D01*
G02X281222I1723J1950D01*
G37*
G36*
G01X75192Y1811631D02*
G02X71048Y1808122I-4144J692D01*
G01X66748D01*
G02Y1816524I0J4201D01*
G01X67864D01*
G03X68264Y1816918I0J400D01*
G02X68381Y1817194I400J-7D01*
G01X70134Y1818948D01*
X75679D01*
G02X75949Y1818252I1J-400D01*
G03X77206Y1814267I1550J-1702D01*
G02X77438Y1813587I-51J-397D01*
G01X75931Y1812080D01*
G02X75617Y1811964I-283J283D01*
G03X75192Y1811631I-30J-399D01*
G37*
G36*
G01X151393Y538206D02*
G03X151253Y537973I56J-192D01*
G02X148357Y539710I-2253J-473D01*
G03X148497Y539943I-56J192D01*
G02X149431Y542303I2253J473D01*
G03X149394Y542981I-229J327D01*
G02X151819Y543113I1106J2019D01*
G03X151856Y542435I229J-327D01*
G02X151393Y538206I-1106J-2019D01*
G37*
G36*
G01X150515Y522572D02*
G02X150050Y519589I1485J-1759D01*
G03X149429Y519659I-338J-213D01*
G02X146172Y523681I-1839J1840D01*
G03X146133Y524374I-218J335D01*
G02X148718Y524519I1166J2326D01*
G03X148757Y523826I218J-335D01*
G02X149902Y522694I-1167J-2326D01*
G03X150515Y522572I355J184D01*
G37*
G36*
G01X261765Y1159610D02*
G03X261233I-266J-299D01*
G02Y1163490I-1734J1940D01*
G03X261765I266J299D01*
G02X265449Y1163273I1734J-1940D01*
G03X266049I300J264D01*
G02X269733Y1163490I1950J-1723D01*
G03X270265I266J299D01*
G02Y1159610I1734J-1940D01*
G03X269733I-266J-299D01*
G02X266049Y1159827I-1734J1940D01*
G03X265449I-300J-264D01*
G02X261765Y1159610I-1950J1723D01*
G37*
G36*
G01X262294Y1151085D02*
G03X261761Y1151077I-262J-302D01*
G02X261704Y1154957I-1762J1915D01*
G03X262237Y1154965I262J302D01*
G02X265949Y1154773I1762J-1915D01*
G03X266549I300J264D01*
G02X270233Y1154990I1950J-1723D01*
G03X270765I266J299D01*
G02Y1151110I1734J-1940D01*
G03X270233I-266J-299D01*
G02X266549Y1151327I-1734J1940D01*
G03X265949I-300J-264D01*
G02X262294Y1151085I-1950J1723D01*
G37*
G36*
G01X228819Y1094506D02*
X228833Y1094481D01*
X235702Y1087612D01*
Y1066773D01*
X235710Y1066746D01*
G02X231290I-2210J-646D01*
G01X231298Y1066773D01*
Y1071131D01*
G03X230736Y1071497I-400J1D01*
G02Y1075703I-936J2103D01*
G03X231298Y1076069I162J365D01*
G01Y1085788D01*
X225719Y1091367D01*
X225694Y1091381D01*
G02X228819Y1094506I1106J2019D01*
G37*
G36*
G01X125688Y1052486D02*
G03Y1052214I147J-136D01*
G02X122310I-1689J-1564D01*
G03Y1052486I-147J136D01*
G02X125688I1689J1564D01*
G37*
G36*
G01X217549Y937890D02*
G03X216949I-300J-264D01*
G02X213276Y941563I-1950J1723D01*
G03Y942163I-264J300D01*
G02Y946063I1723J1950D01*
G03Y946663I-264J300D01*
G02X216949Y950336I1723J1950D01*
G03X217549I300J264D01*
G02X221062Y946533I1950J-1723D01*
G03Y945893I240J-320D01*
G02X221358Y941993I-1563J-2080D01*
G03Y941433I286J-280D01*
G02X217549Y937890I-1859J-1820D01*
G37*
G36*
G01X87859Y939073D02*
G03X87891Y938803I162J-118D01*
G02X84539Y938406I-1492J-1753D01*
G03X84507Y938676I-162J118D01*
G02X87859Y939073I1492J1753D01*
G37*
G36*
G01X153633Y934525D02*
G03X153699Y933859I251J-311D01*
G02X150865Y933575I-1200J-2309D01*
G03X150799Y934241I-251J311D01*
G02X153633Y934525I1200J2309D01*
G37*
G36*
G01X110639Y930215D02*
G03X110659Y929942I156J-126D01*
G02X107305Y929692I-1560J-1692D01*
G03X107285Y929965I-156J126D01*
G02X110639Y930215I1560J1692D01*
G37*
G36*
G01X95178Y903845D02*
X95270Y903838D01*
X111408Y919976D01*
X151690D01*
X151750Y920046D01*
G02Y917054I1749J-1496D01*
G01X151690Y917124D01*
X112590D01*
X97287Y901821D01*
X97294Y901729D01*
G02X95178Y903845I-2295J-179D01*
G37*
G36*
G01X217696Y885577D02*
G03X217629Y885044I261J-303D01*
G02X213802Y885523I-2130J-1494D01*
G03X213869Y886056I-261J303D01*
G02X217949Y889273I2130J1494D01*
G03X218549I300J264D01*
G02Y885827I1950J-1723D01*
G03X217949I-300J-264D01*
G02X217696Y885577I-1951J1722D01*
G37*
G36*
G01X145497Y878348D02*
X92001D01*
X89798Y880552D01*
Y889048D01*
X90550Y889800D01*
X90298Y890052D01*
Y894048D01*
X92001Y895752D01*
X136001D01*
X154001Y913752D01*
X161497D01*
X163200Y912048D01*
Y904552D01*
X160082Y901434D01*
G03X160365Y900752I283J-282D01*
G01X168497D01*
X169700Y899548D01*
Y892552D01*
X165997Y888848D01*
X156887D01*
X156840Y888820D01*
G02X155672Y888454I-1340J2230D01*
G01X155597Y888449D01*
X145497Y878348D01*
G37*
G36*
G01X162865Y867752D02*
X168997D01*
X170700Y866048D01*
Y860052D01*
X167497Y856848D01*
X159497D01*
X150497Y847848D01*
X89001D01*
X87298Y849552D01*
Y857048D01*
X89550Y859300D01*
X88798Y860052D01*
Y863548D01*
X90501Y865252D01*
X136001D01*
X151001Y880252D01*
X159497D01*
X163200Y876548D01*
Y869052D01*
X162582Y868434D01*
G03X162865Y867752I283J-282D01*
G37*
G36*
G01X101185Y965726D02*
G02X99456Y967256I-2184J-727D01*
G03X99915Y967774I79J392D01*
G02X101644Y966244I2184J727D01*
G03X101185Y965726I-79J-392D01*
G37*
G36*
G01X207114Y836257D02*
G03X206534I-290J-276D01*
G02X202733Y839811I-1885J1793D01*
G03Y840352I-294J271D01*
G02X202644Y843771I1916J1761D01*
G03X202624Y844304I-308J255D01*
G02X206447Y847832I1872J1807D01*
G03X207047Y847833I300J265D01*
G02X210934Y844373I1953J-1720D01*
G03X210932Y843840I298J-268D01*
G02X210907Y840358I-1946J-1727D01*
G03X210909Y839817I296J-269D01*
G02X207114Y836257I-1910J-1767D01*
G37*
G36*
G01X292264Y350174D02*
G03X291732I-266J-299D01*
G02X288275Y354064I-1734J1940D01*
G03Y354664I-264J300D01*
G02Y358564I1723J1950D01*
G03Y359164I-264J300D01*
G02X291732Y363054I1723J1950D01*
G03X292264I266J299D01*
G02X295721Y359164I1734J-1940D01*
G03Y358564I264J-300D01*
G02Y354664I-1723J-1950D01*
G03Y354064I264J-300D01*
G02X292264Y350174I-1723J-1950D01*
G37*
G36*
G01X309320Y759226D02*
G03X309873Y759058I357J181D01*
G02X309060Y755809I1126J-2008D01*
G03X308494Y755920I-336J-216D01*
G02X309320Y759226I-1495J2130D01*
G37*
G36*
G01X879567Y1458454D02*
G03X879583Y1458171I149J-134D01*
G02X876340Y1457987I-1529J-1721D01*
G03X876324Y1458270I-149J134D01*
G02X879567Y1458454I1529J1721D01*
G37*
G36*
G01X808507Y1108890D02*
G03X808462Y1108202I180J-357D01*
G02X808679Y1104063I-1463J-2152D01*
G03X808725Y1103419I259J-305D01*
G02X809281Y1099481I-1384J-2204D01*
G03X809302Y1098926I298J-267D01*
G02X809356Y1098872I-1812J-1867D01*
G03X809642I143J140D01*
G02X809765Y1095110I1857J-1822D01*
G03X809233I-266J-299D01*
G02X805186Y1095858I-1734J1940D01*
G03X804520Y1095927I-356J-183D01*
G02X800765Y1095626I-2021J1639D01*
G03X800233I-266J-299D01*
G02Y1099506I-1734J1940D01*
G03X800765I266J299D01*
G02X804812Y1098758I1734J-1940D01*
G03X805478Y1098689I356J183D01*
G02X805559Y1098785I2029J-1630D01*
G03X805538Y1099340I-298J267D01*
G02X805661Y1103203I1803J1876D01*
G03X805615Y1103847I-259J305D01*
G02X805833Y1108376I1384J2203D01*
G03X805878Y1109064I-180J357D01*
G02X805901Y1113383I1463J2152D01*
G03Y1114049I-222J333D01*
G02X808781I1440J2167D01*
G03Y1113383I222J-333D01*
G02X808507Y1108890I-1440J-2167D01*
G37*
G36*
G01X848791Y1063187D02*
G03X849324Y1063179I271J294D01*
G02X849275Y1059746I1509J-1738D01*
G03X848742Y1059754I-271J-294D01*
G02X848791Y1063187I-1509J1738D01*
G37*
G36*
G01X879771Y1053059D02*
G03X879793Y1052788I157J-124D01*
G02X876426Y1052521I-1560J-1693D01*
G03X876404Y1052792I-157J124D01*
G02X879771Y1053059I1560J1693D01*
G37*
G36*
G01X868187Y1377460D02*
G02X864515Y1374811I-1591J-1664D01*
G03X863813Y1374849I-361J-171D01*
G02X863930Y1377035I-1964J1201D01*
G03X864632Y1376997I361J171D01*
G02X865094Y1377540I1963J-1202D01*
G03X865109Y1378132I-261J303D01*
G02X868202Y1378052I1591J1664D01*
G03X868187Y1377460I261J-303D01*
G37*
G54D24*
X895669Y1975079D03*
Y1801851D03*
Y1569567D03*
Y758543D03*
Y585315D03*
Y353031D03*
Y179803D03*
X167323Y1975079D03*
Y353031D03*
Y179803D03*
X68898Y190275D03*
Y17047D03*
Y595787D03*
X167323Y585315D03*
Y758543D03*
X68898Y1001299D03*
Y828071D03*
X167323Y1569567D03*
Y1396339D03*
Y1164055D03*
X68898Y1233583D03*
X167323Y1801851D03*
Y990827D03*
G54D29*
X47499Y1915050D03*
Y1930550D03*
X62499Y1939550D03*
X58999Y1958050D03*
X62999Y1914550D03*
Y1926050D03*
X81499Y1915550D03*
X82499Y1957050D03*
X73499D03*
X66499D03*
X73499Y1945550D03*
X97999Y199050D03*
X83999Y1945050D03*
X92499Y1959050D03*
X116400Y56000D03*
X114800Y68500D03*
X119999Y1978550D03*
X119499Y1972550D03*
X127499Y65050D03*
X141999Y65550D03*
X129999Y78050D03*
X127999Y99550D03*
X127499Y1978550D03*
X133499D03*
X132999Y1972550D03*
X126999D03*
X167499Y43550D03*
X156499Y66050D03*
X155999Y181050D03*
X183499Y45550D03*
X208499Y45650D03*
X199999Y46050D03*
X192499Y57550D03*
X225499Y46550D03*
X226999Y1941050D03*
X294100Y28000D03*
X563499Y1503550D03*
X717000Y1812384D03*
X751499Y679148D03*
X757500Y1522500D03*
X773999Y1923550D03*
X767999Y1923050D03*
X799385Y761436D03*
X839999Y46050D03*
X840499Y55050D03*
X840999Y62550D03*
X841499Y71550D03*
X837999Y91050D03*
X838499Y107050D03*
Y99550D03*
X839499Y119050D03*
X865499Y39550D03*
X854499D03*
X856499Y71050D03*
X855499Y82050D03*
X845999Y111050D03*
X865499Y125550D03*
X864414Y1940050D03*
X883999Y39050D03*
X881499Y70550D03*
X866999D03*
X876999Y82050D03*
X867499D03*
X875499Y125550D03*
X866499Y724550D03*
X902999Y22050D03*
X902499Y35050D03*
X904499Y74050D03*
X904999Y67550D03*
X904814Y1789113D03*
X917499Y21550D03*
X909499D03*
X909999Y35550D03*
X916499Y36050D03*
X929999Y32550D03*
X943499Y48050D03*
Y55050D03*
X950100Y1626100D03*
X36499Y732550D03*
X97300Y1564100D03*
X122600Y1565000D03*
X180000Y1619600D03*
X260999Y1503550D03*
X266999Y1512550D03*
X151300Y1049300D03*
X326301Y1766030D03*
X305998Y352114D03*
X873499Y1356050D03*
G54D23*
X802099Y1961950D03*
X804899Y1556950D03*
X14999Y1936050D03*
X8499Y1937550D03*
X15099Y1944050D03*
X11703Y1951946D03*
X17499Y1961050D03*
X25499Y1956050D03*
X32999Y1960555D03*
X31799Y1979050D03*
X45800Y405200D03*
X57999Y1891050D03*
X42499Y1902550D03*
X48499Y1897050D03*
X50499Y1961550D03*
X43462Y1961160D03*
X65999Y216050D03*
X95350Y204550D03*
X89800Y208550D03*
X154200Y168500D03*
X149400Y166400D03*
X175499Y86572D03*
X176399Y94872D03*
X186999Y99050D03*
X188999Y120800D03*
X173500Y166315D03*
X230749Y76300D03*
X213499Y104650D03*
X223499Y108150D03*
X218499Y190550D03*
X223436Y1890465D03*
X218100Y1886400D03*
X214999Y1909550D03*
X213138Y1952703D03*
X210999Y1942050D03*
X233749Y110800D03*
X237899Y107050D03*
X247800Y269700D03*
X250300Y275100D03*
X231999Y1914050D03*
X249499Y1928050D03*
X253871Y291410D03*
X264499Y1964050D03*
X293999Y293550D03*
X308999Y87050D03*
X315800Y100500D03*
X324800Y89400D03*
X323400Y105200D03*
X354999Y72050D03*
X358999Y61550D03*
X365499Y86550D03*
X394199Y45050D03*
X707600Y1815600D03*
X732549Y1806634D03*
X733149Y1798634D03*
X733049Y1814134D03*
X757499Y1079550D03*
X757999Y1484050D03*
X758499Y1893550D03*
X771105Y722789D03*
X784499Y1529050D03*
X802499Y1951550D03*
X800431Y1941193D03*
X794499Y1941050D03*
X782999Y1937050D03*
X809940Y264940D03*
X822100Y261700D03*
Y279500D03*
X820600Y664300D03*
X808660Y667540D03*
X813200Y675900D03*
X822100Y1466800D03*
X809960Y1478040D03*
X814700Y1486300D03*
X822700Y1871100D03*
X810900Y1882440D03*
X805900Y1887560D03*
X842499Y280924D03*
X827500Y274500D03*
X829800Y666650D03*
X827700Y1487600D03*
X828500Y1877800D03*
X865499Y288050D03*
X862800Y1712700D03*
X863699Y1906450D03*
X857099Y1917650D03*
X868799Y294750D03*
X867899Y321550D03*
X868299Y336150D03*
X879750Y570550D03*
X879708Y971892D03*
X886439Y1717600D03*
X873800Y1733600D03*
X907499Y131800D03*
X889800Y1711500D03*
X926999Y122050D03*
X910999Y124550D03*
X916499Y172550D03*
X917499Y1796550D03*
X938499Y115550D03*
X961499Y93350D03*
X986400Y1639302D03*
X987100Y1624900D03*
X981200Y1625800D03*
X984211Y1667500D03*
X834799Y1946950D03*
X343499Y31650D03*
X20999Y1320550D03*
X163549Y517100D03*
X171722Y513827D03*
X58699Y837250D03*
X63499Y843050D03*
X176799Y493850D03*
X246800Y677100D03*
X249700Y682500D03*
X238500Y680800D03*
X249800Y689900D03*
X254499Y697700D03*
X65599Y514250D03*
X76999Y1196550D03*
X103999Y1216863D03*
X103686Y1223863D03*
X101541Y1262607D03*
X101399Y1292550D03*
X102700Y1321363D03*
X98599Y1491350D03*
X100699Y1471050D03*
X100000Y1546650D03*
X90324Y1538800D03*
X119399Y1298113D03*
X116999Y1288050D03*
X120507Y1317050D03*
X107999Y1307713D03*
X119499Y1339050D03*
X106999Y1454450D03*
X138600Y1124600D03*
X135850Y1322250D03*
X129000Y1356500D03*
X147400Y1321600D03*
X152633Y1677967D03*
X181100Y1682700D03*
X177900Y1690400D03*
X74400Y1574800D03*
X95499Y1665418D03*
X93999Y1703050D03*
X118499Y1694050D03*
X117499Y1706050D03*
X122642Y1704243D03*
X123749Y1711550D03*
X128749Y1703300D03*
X199149Y1362900D03*
X194700Y1385700D03*
X224750Y1483950D03*
X229025Y1471576D03*
X241000Y1469600D03*
X233700Y1481600D03*
X261999Y1516050D03*
X295000Y1513000D03*
X108200Y963600D03*
X163500Y937100D03*
X154749Y968249D03*
X172500Y919294D03*
X211750Y894600D03*
X221800Y1069300D03*
X242000Y1066000D03*
X247500Y1085500D03*
X251500Y1136700D03*
X269500Y1135500D03*
X282500Y1135000D03*
X164700Y1085400D03*
X301249Y346050D03*
X350499Y597300D03*
X864499Y1128750D03*
X807000Y1072900D03*
X815400Y1078800D03*
X825700Y1083100D03*
X825800Y1072300D03*
X803199Y1151850D03*
G54D26*
X78150Y178464D03*
X158071Y191614D03*
Y341220D03*
Y1963268D03*
X886417Y191614D03*
Y341220D03*
Y597126D03*
Y746732D03*
Y1557756D03*
Y1813662D03*
Y1963268D03*
X78150Y583976D03*
Y1245394D03*
Y1395000D03*
X158071Y1152244D03*
Y1408150D03*
Y1557756D03*
X78150Y1650906D03*
X158071Y1002638D03*
X886417D03*
Y1152244D03*
Y1408150D03*
G54D28*
X29531Y309549D03*
X17720Y1903132D03*
X271657Y267699D03*
X994098Y149588D03*
Y673210D03*
Y1068880D03*
X271657Y673210D03*
Y1484234D03*
Y1078722D03*
G54D25*
X9843Y353144D03*
Y1859468D03*
Y875216D03*
Y1337396D03*
G54D27*
X1019291Y1416024D03*
G54D30*
X994093Y1889751D03*
%LPD*%
G75*
G36*
G01X83251Y77848D02*
X98548Y62552D01*
Y52324D01*
G02X97994Y51954I-400J-1D01*
G03X96119Y51999I-996J-2404D01*
G02X95586Y52332I-136J376D01*
G03X93879Y49601I-2587J-282D01*
G02X94412Y49268I136J-376D01*
G03X97994Y47146I2587J282D01*
G02X98548Y46776I154J-369D01*
G01Y43130D01*
G02X97981Y42767I-400J1D01*
G03X94836Y41985I-1081J-2367D01*
G02X94303Y41891I-318J243D01*
G03X94243Y41929I-1422J-2179D01*
G02X94256Y42621I207J342D01*
G03X91657Y42671I-1256J2279D01*
G02X91644Y41979I-207J-342D01*
G03X90548Y38587I1256J-2279D01*
G01X90567Y38546D01*
Y38302D01*
X90098D01*
X81700Y46699D01*
Y64052D01*
X85700Y68052D01*
Y74548D01*
X82741Y77507D01*
G02X82882Y77848I142J141D01*
G01X83251D01*
G37*
G36*
G01X123342Y25050D02*
X94999D01*
X94974Y25074D01*
X89026D01*
X71499Y42601D01*
Y76050D01*
X72499Y77050D01*
X81499D01*
X84499Y74050D01*
Y68550D01*
X80499Y64550D01*
Y46201D01*
X89600Y37100D01*
X92802D01*
G03X92998I98J2600D01*
G01X94881D01*
G02X95270Y36607I0J-400D01*
G03X100330I2530J-607D01*
G02X100719Y37100I389J93D01*
G01X134949D01*
X135024Y37024D01*
X137376D01*
X147350Y27050D01*
X148701D01*
X148902Y26848D01*
X257997D01*
X258198Y27050D01*
X258499D01*
X286499Y55050D01*
Y65050D01*
X290499Y69050D01*
X297999D01*
X301499Y72550D01*
Y81550D01*
X302999Y83050D01*
X316499D01*
X316999Y82550D01*
Y66050D01*
X310999Y60050D01*
X305499D01*
X263999Y18550D01*
X143096D01*
G03X139973Y20948I-3123J-835D01*
G01X139227D01*
G03X123399Y25100I-9306J-3232D01*
G01X123342Y25050D01*
G37*
G36*
G01X149400Y28050D02*
X138250Y39200D01*
X102900D01*
X99749Y42351D01*
Y63050D01*
X83749Y79050D01*
X71499D01*
X70999Y79550D01*
Y86050D01*
X71499Y86550D01*
X87999D01*
X107999Y66550D01*
Y53800D01*
X108000D01*
X110100Y51700D01*
X144800D01*
X160450Y36050D01*
X245371D01*
X245431Y35971D01*
G03X249567I2068J1579D01*
G01X249627Y36050D01*
X252499D01*
X278499Y62050D01*
Y78050D01*
X283499Y83050D01*
X297499D01*
X297999Y82550D01*
Y72550D01*
X296499Y71050D01*
X291999D01*
X291499Y70550D01*
X287999D01*
X284999Y67550D01*
Y55550D01*
X257499Y28050D01*
X149400D01*
G37*
G36*
G01X150499Y866550D02*
X168499D01*
X169499Y865550D01*
Y860550D01*
X166999Y858050D01*
X158999D01*
X149999Y849050D01*
X89499D01*
X88499Y850050D01*
Y856550D01*
X90499Y858550D01*
X142499D01*
X150499Y866550D01*
G37*
G36*
G01X90798Y859752D02*
X89999Y860550D01*
Y863050D01*
X90999Y864050D01*
X136499D01*
X151499Y879050D01*
X158999D01*
X161999Y876050D01*
Y869550D01*
X160499Y868050D01*
X148999D01*
X140700Y859752D01*
X90798D01*
G37*
G36*
G01X91499Y889050D02*
X141999D01*
X152499Y899550D01*
X167999D01*
X168499Y899050D01*
Y893050D01*
X165499Y890050D01*
X155499D01*
X144999Y879550D01*
X92499D01*
X90999Y881050D01*
Y888550D01*
X91499Y889050D01*
G37*
G36*
G01X91797Y890252D02*
X91499Y890550D01*
Y893550D01*
X92499Y894550D01*
X136499D01*
X154499Y912550D01*
X160999D01*
X161999Y911550D01*
Y905050D01*
X158999Y902050D01*
X151499D01*
X139700Y890252D01*
X91797D01*
G37*
G54D10*
X-38436Y23633D03*
X-36811Y1104775D03*
X-35919Y1969497D03*
X9843Y353144D03*
Y717711D03*
Y762617D03*
Y875216D03*
Y1337396D03*
Y1701963D03*
Y1746869D03*
Y1859468D03*
X78150Y28858D03*
Y178464D03*
Y434370D03*
Y583976D03*
Y839882D03*
Y989488D03*
Y1245394D03*
Y1395000D03*
Y1650906D03*
Y1800512D03*
X158071Y191614D03*
Y341220D03*
Y597126D03*
Y746732D03*
Y1002638D03*
Y1152244D03*
Y1408150D03*
Y1557756D03*
Y1813662D03*
Y1963268D03*
X886417Y191614D03*
Y341220D03*
Y597126D03*
Y746732D03*
Y1002638D03*
Y1152244D03*
Y1408150D03*
Y1557756D03*
Y1813662D03*
Y1963268D03*
X1019291Y1416024D03*
Y1694212D03*
X1072493Y21507D03*
X1075940Y1769358D03*
G54D20*
G01X60003Y534150D02*
X60074Y534221D01*
G02X62399Y535184I2325J-2325D01*
G01X70044D01*
G02X72299Y534250I0J-3189D01*
G01X80457Y526092D01*
G03X83455Y524850I2998J2997D01*
G01X87099D01*
Y524851D01*
G03X89148Y525697I4J2896D01*
G01X89650Y526201D01*
X90749Y527300D01*
G03X91499Y529111I-1812J1811D01*
G01Y532943D01*
G03X91003Y534145I-1700J2D01*
G01X90694Y534454D01*
G03X89492Y534950I-1200J-1204D01*
G01X87594D01*
G02X87047Y535176I-1J773D01*
G01X86199Y536025D01*
G01X59999Y537550D02*
X60504Y537044D01*
G03X62099Y536384I1594J1595D01*
G01X69999D01*
G02X73181Y535066I0J-4500D01*
G01X81307Y526940D01*
G03X83456Y526050I2149J2149D01*
G01X87099D01*
G03X88298Y526546I1J1695D01*
G01X88800Y527049D01*
X89900Y528149D01*
G03X90299Y529112I-963J963D01*
G01Y532943D01*
G03X90153Y533296I-500J0D01*
G01X89845Y533604D01*
G03X89492Y533750I-353J-354D01*
G01X87023D01*
G03X86299Y533450I0J-1024D01*
G01X86199Y533350D01*
G03Y532250I550J-550D01*
G01X124423Y1077523D02*
X123673Y1078272D01*
G03X122400Y1078800I-1274J-1273D01*
G03X120860Y1078162I0J-2178D01*
G01X99599Y1056901D01*
G03X98450Y1054127I2774J-2774D01*
G01Y989993D01*
G02X96591Y985508I-6345J2D01*
G01X96592Y985507D01*
X86537Y975452D01*
G03X84900Y971500I3952J-3952D01*
G01Y947162D01*
G02X83798Y944502I-3761J0D01*
G01X83799Y944501D01*
X81591Y942293D01*
G03X80600Y939900I2394J-2393D01*
G01Y932923D01*
G03X81749Y930149I3923J0D01*
G01X83249Y928649D01*
X83248Y928648D01*
G02X85099Y924180I-4467J-4468D01*
G01Y716999D01*
G02X83257Y712551I-6292J0D01*
G01X69853Y699147D01*
X69852Y699148D01*
G02X64428Y696901I-5424J5423D01*
G01X53066D01*
G03X50410Y695801I0J-3756D01*
G01X50300Y699200D02*
G03X52953Y698101I2653J2653D01*
G01X64429D01*
G03X69004Y699996I0J6470D01*
G01X82408Y713400D01*
G03X83899Y717000I-3601J3600D01*
G01Y924181D01*
G03X82400Y927800I-5118J0D01*
G01X80900Y929300D01*
X80901Y929301D01*
G02X79400Y932924I3622J3623D01*
G01Y939901D01*
G02X80742Y943142I4585J0D01*
G01X82950Y945350D01*
G03X83700Y947161I-1811J1811D01*
G01Y971501D01*
G02X85688Y976301I6789J0D01*
G01X95743Y986356D01*
G03X97250Y989994I-3638J3638D01*
G01Y1054126D01*
G02X98751Y1057749I5123J0D01*
G01X98750Y1057750D01*
X120011Y1079011D01*
G02X122399Y1080000I2388J-2389D01*
G01X122400D01*
G03X123844Y1080598I0J2042D01*
G01X124423Y1081177D01*
G01X47000Y1737100D02*
X46278Y1736378D01*
G03X45500Y1734500I1878J-1878D01*
G01Y1733477D01*
G02X45023Y1732325I-1629J0D01*
G01X44099Y1731401D01*
G03X42700Y1728024I3377J-3377D01*
G01Y1724000D01*
G03X43762Y1721436I3626J0D01*
G01X45099Y1720099D01*
G03X47752Y1719000I2653J2653D01*
G01X67041D01*
G03X70901Y1720599I0J5459D01*
G01X75201Y1724899D01*
G02X81001Y1727300I5798J-5800D01*
G01X121078D01*
G02X127598Y1724598I-2J-9223D01*
G01X127599Y1724599D01*
X144515Y1707683D01*
G02X147200Y1701198I-6484J-6483D01*
G01Y1678184D01*
G03X149099Y1673599I6484J0D01*
G01X165849Y1656849D01*
X165848Y1656848D01*
G02X168200Y1651173I-5676J-5677D01*
G01Y1597499D01*
G02X165021Y1589823I-10857J0D01*
G01X138284Y1563086D01*
G03X135349Y1556000I7086J-7086D01*
G01Y1352499D01*
G02X133336Y1347638I-6876J0D01*
G01X132849Y1347151D01*
G02X129411Y1345727I-3438J3439D01*
G01X116462D01*
G03X113500Y1344500I0J-4189D01*
G01Y1348154D02*
G03X116462Y1346927I2962J2962D01*
G01X129410D01*
G03X132000Y1348000I0J3663D01*
G01X132487Y1348487D01*
G03X134149Y1352500I-4014J4013D01*
G01Y1367874D01*
G03X133825Y1368198I-324J0D01*
G01X133824D01*
G02X133500Y1368522I0J324D01*
G01Y1370274D01*
G02X133824Y1370598I324J0D01*
G01X133825D01*
G03X134149Y1370922I0J324D01*
G01Y1372674D01*
G03X133825Y1372998I-324J0D01*
G01X133824D01*
G02X133500Y1373322I0J324D01*
G01Y1375074D01*
G02X133824Y1375398I324J0D01*
G01X133825D01*
G03X134149Y1375722I0J324D01*
G01Y1533970D01*
G03X133825Y1534294I-324J0D01*
G01X133824D01*
G02X133500Y1534618I0J324D01*
G01Y1536370D01*
G02X133824Y1536694I324J0D01*
G01X133825D01*
G03X134149Y1537018I0J324D01*
G01Y1538770D01*
G03X133825Y1539094I-324J0D01*
G01X133824D01*
G02X133500Y1539418I0J324D01*
G01Y1541170D01*
G02X133824Y1541494I324J0D01*
G01X133825D01*
G03X134149Y1541818I0J324D01*
G01Y1543570D01*
G03X133825Y1543894I-324J0D01*
G01X133824D01*
G02X133500Y1544218I0J324D01*
G01Y1545970D01*
G02X133824Y1546294I324J0D01*
G01X133825D01*
G03X134149Y1546618I0J324D01*
G01Y1555999D01*
G02X137435Y1563935I11221J2D01*
G01X164172Y1590672D01*
G03X167000Y1597500I-6829J6828D01*
G01Y1651172D01*
G03X165000Y1656000I-6828J0D01*
G01X148250Y1672750D01*
X148251Y1672751D01*
G02X146000Y1678185I5433J5434D01*
G01Y1701199D01*
G03X143666Y1706834I-7969J0D01*
G01X126750Y1723750D01*
G03X121077Y1726100I-5673J-5673D01*
G01X81000D01*
G03X76050Y1724050I0J-7001D01*
G01X71750Y1719750D01*
X71749Y1719751D01*
G02X67042Y1717800I-4709J4708D01*
G01X47751D01*
G02X44251Y1719251I2J4952D01*
G01X44250Y1719250D01*
X42913Y1720587D01*
G02X41500Y1724001I3413J3412D01*
G01Y1728025D01*
G02X43251Y1732249I5976J-2D01*
G01X43250Y1732250D01*
X44174Y1733174D01*
G03X44299Y1733477I-303J302D01*
G01X44300Y1733476D01*
Y1735450D01*
G03X43628Y1737072I-2294J0D01*
G01X43600Y1737100D01*
G01X45877Y1728477D02*
G03X48839Y1727250I2962J2962D01*
G01X66293D01*
G03X70152Y1728848I0J5458D01*
G01X70151Y1728849D01*
X71701Y1730399D01*
G02X77501Y1732800I5798J-5800D01*
G01X110085D01*
G03X112004Y1733595I0J2714D01*
G01X118554Y1740145D01*
X118555Y1740144D01*
G02X122306Y1741699I3753J-3752D01*
G01X183443D01*
G02X186593Y1740393I-2J-4457D01*
G01X186594Y1740394D01*
X188994Y1737994D01*
G02X190274Y1734902I-3092J-3091D01*
G01Y1123372D01*
G02X188298Y1118602I-6745J0D01*
G01X188299Y1118601D01*
X150210Y1080512D01*
G02X146001Y1078769I-4209J4211D01*
G01X140407D01*
G03X137481Y1077557I0J-4138D01*
G01X137477Y1081177D02*
G03X140393Y1079969I2916J2916D01*
G01X146000D01*
G03X149361Y1081361I0J4754D01*
G01X187450Y1119450D01*
G03X189074Y1123371I-3921J3921D01*
G01Y1327764D01*
G03X188787Y1328051I-287J0D01*
G02X188500Y1328338I0J287D01*
G01Y1330164D01*
G02X188787Y1330451I287J0D01*
G03X189074Y1330738I0J287D01*
G01Y1332564D01*
G03X188787Y1332851I-287J0D01*
G02X188500Y1333138I0J287D01*
G01Y1334964D01*
G02X188787Y1335251I287J0D01*
G03X189074Y1335538I0J287D01*
G01Y1603283D01*
G03X188787Y1603570I-287J0D01*
G02X188500Y1603857I0J287D01*
G01Y1605683D01*
G02X188787Y1605970I287J0D01*
G03X189074Y1606257I0J287D01*
G01Y1608083D01*
G03X188787Y1608370I-287J0D01*
G02X188500Y1608657I0J287D01*
G01Y1610483D01*
G02X188787Y1610770I287J0D01*
G03X189074Y1611057I0J287D01*
G01Y1734902D01*
G03X188145Y1737145I-3172J0D01*
G01X185745Y1739545D01*
G03X183442Y1740499I-2303J-2303D01*
G01X122307D01*
G03X119403Y1739296I0J-4107D01*
G01X112853Y1732746D01*
X112852Y1732747D01*
G02X110086Y1731600I-2768J2767D01*
G01X96590D01*
G03X96290Y1731300I0J-300D01*
G02X95990Y1731000I-300J0D01*
G01X94190D01*
G02X93890Y1731300I0J300D01*
G03X93590Y1731600I-300J0D01*
G01X91790D01*
G03X91490Y1731300I0J-300D01*
G02X91190Y1731000I-300J0D01*
G01X89390D01*
G02X89090Y1731300I0J300D01*
G03X88790Y1731600I-300J0D01*
G01X86990D01*
G03X86690Y1731300I0J-300D01*
G02X86390Y1731000I-300J0D01*
G01X84590D01*
G02X84290Y1731300I0J300D01*
G03X83990Y1731600I-300J0D01*
G01X77500D01*
G03X72550Y1729550I0J-7001D01*
G01X71000Y1728000D01*
G02X66292Y1726050I-4708J4708D01*
G01X48839D01*
G03X45877Y1724823I0J-4189D01*
G01X62503Y470946D02*
X62788Y471231D01*
G02X64299Y471857I1511J-1511D01*
G01X69345D01*
G03X72348Y473101I0J4247D01*
G01X131198Y531951D01*
X133626Y534378D01*
G03X136099Y540350I-5972J5971D01*
G01Y578497D01*
G03X133799Y584050I-7853J0D01*
G03X130178Y585550I-3621J-3621D01*
G01X123099D01*
G02X120499Y588150I0J2600D01*
G01Y617376D01*
G02X120699Y617576I200J0D01*
G03X120899Y617776I0J200D01*
G01Y619776D01*
G03X120699Y619976I-200J0D01*
G02X120499Y620176I0J200D01*
G01Y623229D01*
G02X121999Y626850I5121J0D01*
G02X123448Y627450I1449J-1449D01*
G01X130668D01*
G03X132599Y628250I0J2731D01*
G03X133599Y630664I-2414J2414D01*
G01Y639534D01*
G02X134248Y641101I2216J0D01*
G01X138848Y645701D01*
G02X140415Y646350I1567J-1567D01*
G01X143244D01*
G02X144238Y645356I0J-994D01*
G01X62497Y474346D02*
X63494Y473349D01*
G03X64199Y473057I705J705D01*
G01X69343D01*
G03X71499Y473950I0J3049D01*
G01X130349Y532800D01*
X132777Y535227D01*
G03X134898Y540350I-5124J5122D01*
G01X134899Y540349D01*
Y578498D01*
X134898Y578497D01*
G03X132950Y583201I-6652J0D01*
G03X130177Y584350I-2773J-2772D01*
G01X123099D01*
G02X119299Y588150I0J3800D01*
G01Y623230D01*
G02X121150Y627699I6321J0D01*
G02X123449Y628650I2297J-2298D01*
G01X130667D01*
G03X131750Y629099I0J1531D01*
G03X132399Y630665I-1565J1566D01*
G01Y639534D01*
G02X133399Y641950I3416J1D01*
G01X137999Y646550D01*
G02X140415Y647550I2415J-2416D01*
G01X142657D01*
G03X144238Y649131I0J1581D01*
G01X62978Y486217D02*
G02X64266Y487505I1288J0D01*
G01X78819D01*
G03X82372Y488976I1J5024D01*
G01X111622Y518226D01*
G03X112823Y521126I-2901J2900D01*
G01Y625569D01*
G02X114099Y628650I4357J0D01*
G01X120949Y635500D01*
X121162Y635714D01*
G02X122699Y636350I1536J-1537D01*
G01X123799D01*
G02X125336Y635714I1J-2173D01*
G01X125499Y635550D01*
G01X63067Y489616D02*
G03X63978Y488705I911J0D01*
G01X78819D01*
G03X81523Y489825I0J3824D01*
G01X110773Y519075D01*
G03X111623Y521127I-2052J2052D01*
G01Y625569D01*
G02X113250Y629499I5557J1D01*
G01X120098Y636347D01*
X120312Y636562D01*
G02X122699Y637549I2384J-2386D01*
G01Y637550D01*
X123799D01*
G03X124311Y637762I0J724D01*
G01X125499Y638950D01*
G54D11*
X17600Y5604D03*
X10000Y16500D03*
X11999Y53550D03*
X11499Y34050D03*
X11999Y69050D03*
Y88550D03*
X11499Y106050D03*
X11999Y124550D03*
X11499Y142050D03*
X11999Y177050D03*
Y161550D03*
Y196550D03*
X11499Y214050D03*
X9499Y229050D03*
X8999Y246550D03*
X9499Y281550D03*
Y266050D03*
Y301050D03*
X15499Y328050D03*
X8999Y318550D03*
X15499Y342550D03*
Y360050D03*
X14799Y751450D03*
X8599Y751650D03*
X17299Y773950D03*
X10999Y774050D03*
X8999Y889550D03*
X8499Y907050D03*
X8999Y942050D03*
Y926550D03*
Y961550D03*
X8499Y979050D03*
X8999Y988550D03*
Y1025550D03*
X8499Y1006050D03*
X8999Y1041050D03*
Y1060550D03*
X8499Y1089050D03*
Y1078050D03*
X7999Y1106550D03*
X8499Y1126050D03*
Y1141550D03*
Y1161050D03*
X7999Y1192550D03*
Y1178550D03*
X7499Y1210050D03*
X7999Y1229550D03*
Y1245050D03*
Y1264550D03*
X7499Y1282050D03*
X8299Y1320050D03*
X8799Y1302550D03*
X18099Y1343550D03*
X9399Y1347350D03*
X15299Y1723450D03*
X15399Y1708350D03*
X7099Y1717750D03*
X7199Y1731450D03*
X14899Y1736250D03*
X15299Y1753250D03*
X6099Y1753750D03*
X11299Y1850050D03*
X9099Y1881550D03*
X8499Y1979550D03*
X11500Y1987000D03*
X36000Y5604D03*
X23499Y27050D03*
X40999Y27550D03*
X27799Y38450D03*
X40999Y42050D03*
X25799Y64050D03*
X28399Y94950D03*
X34999Y108550D03*
X41399Y134150D03*
X27999Y131050D03*
Y145550D03*
Y163050D03*
X23999Y243550D03*
Y229050D03*
Y261050D03*
X39999Y327550D03*
Y342050D03*
Y359550D03*
Y576550D03*
X36999Y725050D03*
Y719550D03*
X37499Y714050D03*
X41499Y719550D03*
X26399Y750850D03*
X36499Y740050D03*
Y732550D03*
X39899Y754850D03*
X39399Y768750D03*
X27199Y764950D03*
X28599Y775450D03*
X26799Y874550D03*
X26099Y891650D03*
X25699Y916150D03*
X25099Y942150D03*
X23899Y957950D03*
X24799Y992250D03*
X33899Y1005950D03*
X21499Y1073250D03*
X21399Y1090850D03*
X21299Y1300250D03*
X21799Y1282750D03*
X31499Y1849750D03*
X39399Y1864350D03*
X23999Y1857950D03*
X27199Y1874350D03*
X34799Y1890050D03*
X26500Y1987000D03*
X55700Y5900D03*
X50999Y21150D03*
Y47750D03*
X59499Y90550D03*
Y76050D03*
Y108050D03*
X52499Y130550D03*
Y145050D03*
Y162550D03*
X41699Y183250D03*
X48499Y243050D03*
Y228550D03*
Y260550D03*
X42999Y275650D03*
X51099Y300050D03*
X52199Y342350D03*
X42299Y564150D03*
X62055Y561550D03*
X49555Y563550D03*
X61099Y603236D03*
X52333Y641295D03*
X43499Y657550D03*
X47800Y692800D03*
X53210Y701486D03*
X50999Y720050D03*
X46499Y719550D03*
X51499Y724550D03*
X46499D03*
X41999D03*
X46499Y730550D03*
X41999Y735050D03*
Y731050D03*
X46499Y735050D03*
X41999Y739550D03*
X46499Y739050D03*
X51999Y767050D03*
X47999Y767550D03*
X52499Y771550D03*
X47999D03*
X53999Y791000D03*
X52999Y1871550D03*
X57499Y1871050D03*
X45699Y1875550D03*
X47499Y1915050D03*
Y1930550D03*
X62499Y1939550D03*
X58999Y1958050D03*
X61500Y1987500D03*
X44500Y1987000D03*
X55999Y1982550D03*
X73900Y6200D03*
X65499Y27050D03*
Y41550D03*
Y59050D03*
X77165Y110799D03*
X71015Y123666D03*
X78165Y137116D03*
X75299Y261750D03*
X76099Y414250D03*
X75300Y454100D03*
X67300Y450200D03*
X68899Y445450D03*
X66099Y500950D03*
X77165Y514650D03*
X70800Y540300D03*
X75999Y556640D03*
X72599Y578236D03*
X79299Y794150D03*
X67999Y790400D03*
X76399Y820450D03*
X70100Y818900D03*
X77499Y921550D03*
X77002Y952079D03*
X76711Y948089D03*
X77499Y962152D03*
X72799Y982950D03*
X65799Y994050D03*
X67000Y1011500D03*
X77165Y1327335D03*
X77166Y1353400D03*
X76499Y1507050D03*
Y1498050D03*
Y1512050D03*
Y1503050D03*
X76999Y1528050D03*
Y1519050D03*
X81499Y1589050D03*
X83499Y1594050D03*
X78999Y1593550D03*
X74999D03*
X74499Y1602050D03*
Y1598050D03*
X83499D03*
Y1602050D03*
X78999Y1598050D03*
Y1602050D03*
X83599Y1744750D03*
X77165Y1759550D03*
X78529Y1788113D03*
X78999Y1891550D03*
X82999D03*
Y1887550D03*
X78999D03*
X62999Y1914550D03*
X78999Y1896050D03*
X78433Y1900010D03*
X78999Y1904050D03*
X83499Y1896050D03*
X83433Y1904010D03*
X62999Y1926050D03*
X81499Y1915550D03*
X82499Y1957050D03*
X73499D03*
X66499D03*
X73499Y1945550D03*
X79500Y1987500D03*
X65499Y1982550D03*
X73499D03*
X82999D03*
X90900Y5800D03*
X90899Y14850D03*
X96999Y49550D03*
X92999Y52050D03*
X97800Y36000D03*
X96900Y40400D03*
X93000Y44900D03*
X92900Y39700D03*
X95814Y136065D03*
X96184Y151065D03*
Y166065D03*
X97999Y199050D03*
X92899Y231450D03*
X86899Y242750D03*
X93199Y279650D03*
X84899Y289250D03*
X90899Y309550D03*
X94199Y325550D03*
X93499Y337450D03*
X89899Y368350D03*
X95499Y355450D03*
X89999Y396450D03*
X87599Y403950D03*
X95399Y416350D03*
X89099Y426150D03*
X99399Y437450D03*
X93500Y445300D03*
X97699Y449850D03*
X93199D03*
X97999Y445550D03*
X94500Y456800D03*
X100500Y456700D03*
X98999Y488050D03*
X94499Y486550D03*
X93499Y477050D03*
X97699Y481550D03*
Y477050D03*
X93499Y481550D03*
X101500Y536500D03*
X93599Y581236D03*
X93100Y571640D03*
X92599Y606236D03*
X98001Y856950D03*
X97800Y851800D03*
X93808Y852063D03*
X94001Y856895D03*
X97499Y862050D03*
X93299D03*
X93499Y897152D03*
X93900Y882400D03*
X97900D03*
X97700Y887400D03*
X93690Y887139D03*
X97499Y892550D03*
X93499Y892050D03*
X93000Y907165D03*
X83988Y934028D03*
X86700Y982100D03*
X100999Y1101050D03*
X104999D03*
X100999Y1096550D03*
X102999Y1188050D03*
X104999Y1231050D03*
X100999Y1231032D03*
X103499Y1305050D03*
X93316Y1351000D03*
X96000Y1369000D03*
X96100Y1384650D03*
X97300Y1564100D03*
X92499Y1589050D03*
X86999D03*
X90999Y1628550D03*
Y1624550D03*
X91121Y1632549D03*
X86299Y1632550D03*
X85999Y1628550D03*
Y1624550D03*
X84099Y1737150D03*
X93499Y1759550D03*
X94336Y1773113D03*
X104417Y1791480D03*
X97999Y1815050D03*
X104500Y1813400D03*
X83999Y1900050D03*
Y1945050D03*
X98433Y1940510D03*
X98999Y1944550D03*
X102433Y1940555D03*
X103433Y1944510D03*
X92499Y1959050D03*
X101699Y1983850D03*
X98000Y1987500D03*
X91499Y1983050D03*
X107000Y6000D03*
X116400Y56000D03*
X114800Y68500D03*
X123499Y149050D03*
Y140050D03*
X117500Y162300D03*
X124300Y167800D03*
X109499Y410250D03*
X124899Y409050D03*
X126099Y396150D03*
X111299Y425850D03*
X122499Y427900D03*
X108599Y557236D03*
X108900Y587600D03*
X112200Y762200D03*
X112000Y773000D03*
X111299Y821050D03*
X112999Y901150D03*
X106500Y943000D03*
X105300Y960300D03*
X105006Y1096866D03*
X110999Y1130550D03*
X115200Y1130300D03*
X110999Y1126050D03*
Y1122050D03*
Y1118050D03*
X114999Y1126050D03*
Y1122050D03*
Y1118050D03*
X106999Y1114960D03*
X120999Y1188050D03*
X111999D03*
X121657Y1224604D03*
X120999Y1228550D03*
X120499Y1264550D03*
X123938Y1267623D03*
X117149Y1267550D03*
X123500Y1360300D03*
X122600Y1565000D03*
X124999Y1616050D03*
Y1620050D03*
Y1629050D03*
Y1633050D03*
X119999Y1629050D03*
X120100Y1633100D03*
X122499Y1668550D03*
Y1672550D03*
X118999Y1670550D03*
X105749Y1712749D03*
X117499Y1745050D03*
X123499Y1747050D03*
X120299Y1796150D03*
X111499Y1877550D03*
Y1882550D03*
X122999Y1883050D03*
X115999Y1882550D03*
X116499Y1877550D03*
X122999Y1889050D03*
X124433Y1908510D03*
X124999Y1912550D03*
X119999Y1978550D03*
X119499Y1972550D03*
X108499Y1981750D03*
X115000Y1987000D03*
X129100Y55900D03*
X127499Y65050D03*
X141999Y65550D03*
X129999Y78050D03*
X127999Y99550D03*
X133999Y149050D03*
X142999Y141050D03*
X132999Y141550D03*
X144499Y149050D03*
X131799Y201950D03*
X142688Y218861D03*
X143110Y203861D03*
X133000Y240500D03*
X135399Y277050D03*
X130799Y300250D03*
X130099Y326150D03*
X134699Y356050D03*
X139399Y372350D03*
X127999Y425050D03*
Y421050D03*
Y429550D03*
X133499Y445050D03*
X128999Y445550D03*
X130000Y452000D03*
X135999Y472550D03*
X135140Y478930D03*
X139200Y484300D03*
X134499Y488050D03*
X145649Y509550D03*
X136349Y509050D03*
X140499Y499050D03*
X136299D03*
X147300Y526700D03*
X140000Y587700D03*
X140499Y600550D03*
X143999Y605550D03*
X140499Y626050D03*
X131099Y700450D03*
X139099Y707150D03*
X141234Y1029885D03*
X140864Y1044885D03*
X137900Y1103400D03*
X139100Y1097100D03*
X134500Y1108100D03*
X143200Y1116300D03*
X133200Y1132100D03*
X126400Y1138100D03*
X145900Y1163200D03*
X144399Y1171150D03*
X141499Y1185550D03*
X128400Y1188600D03*
X143899Y1196750D03*
X142499Y1205550D03*
X130999Y1198050D03*
X144149Y1230113D03*
Y1226113D03*
Y1222113D03*
X126499Y1264550D03*
X145999Y1353050D03*
X143199Y1412050D03*
X140799Y1435460D03*
X129100Y1564700D03*
X127200Y1569800D03*
X126562Y1670613D03*
X130499Y1730050D03*
X128000Y1735000D03*
X144499Y1729550D03*
X139500Y1730500D03*
X133000Y1734500D03*
X144499Y1745550D03*
X137999Y1747723D03*
X129999Y1747050D03*
X126599Y1789650D03*
X142144Y1801644D03*
X143490Y1855972D03*
X127499Y1889050D03*
X126999Y1882550D03*
X142499Y1905972D03*
X141499Y1895972D03*
X129999Y1908550D03*
X129433Y1912510D03*
X127499Y1978550D03*
X133499D03*
X132999Y1972550D03*
X126999D03*
X146899Y1961750D03*
X146000Y1987500D03*
X128500D03*
X157299Y5150D03*
X167499Y43550D03*
X156499Y66050D03*
X166999Y88050D03*
X166499Y83550D03*
Y79050D03*
X158499D03*
Y84050D03*
Y88550D03*
Y93550D03*
X166999Y92550D03*
X165499Y106050D03*
X166999Y97050D03*
X152999Y141050D03*
X167499Y149550D03*
X163499Y140050D03*
X160999Y149550D03*
X155999Y181050D03*
X166800Y240800D03*
X158999Y259800D03*
X152808Y246341D03*
X157740Y273924D03*
X167299Y369350D03*
X150699Y411050D03*
X152499Y395950D03*
X149700Y471600D03*
X154100Y476500D03*
X164600Y476700D03*
X153499Y502550D03*
X148999D03*
X147590Y521500D03*
X154099Y529236D03*
X162500Y623400D03*
X152400Y643300D03*
X152124Y651868D03*
X159054Y665400D03*
X161999Y768050D03*
X152499Y810550D03*
Y816050D03*
Y820550D03*
Y825050D03*
X161999Y843550D03*
Y848050D03*
X156499Y846050D03*
X156999Y850050D03*
X156499Y870550D03*
Y876050D03*
X163999Y863050D03*
X159999D03*
X155999Y859050D03*
Y863050D03*
X158114Y883290D03*
X156499Y886950D03*
X159459Y896616D03*
X163499Y896550D03*
X155499Y891050D03*
Y896050D03*
X157499Y904550D03*
Y909050D03*
X151999Y936550D03*
X152499Y931550D03*
X153299Y943750D03*
X159186Y946117D03*
X156499Y985950D03*
X149499Y997650D03*
X162499Y1023550D03*
X158300Y1015000D03*
X163499Y1035050D03*
X159499Y1044579D03*
X151300Y1049300D03*
X165600Y1057428D03*
X168099Y1083550D03*
X164999Y1075550D03*
X159055Y1070400D03*
X167999Y1092850D03*
X167499Y1118550D03*
X167999Y1130550D03*
X163499Y1171650D03*
X151699Y1158550D03*
X151499Y1173050D03*
X150999Y1181150D03*
X148499Y1222113D03*
Y1226113D03*
X148486Y1230113D03*
X167499Y1389050D03*
X156999Y1397750D03*
X166799Y1409350D03*
X157915Y1420460D03*
X163499Y1433350D03*
X165499Y1453550D03*
X166799Y1487450D03*
X159054Y1476200D03*
X167499Y1714113D03*
X162499D03*
X165499Y1730613D03*
X167999Y1726613D03*
X163499D03*
X157500Y1797400D03*
X158000Y1825400D03*
X157999Y1840972D03*
X167200Y1868000D03*
X159054Y1855050D03*
X163599Y1892050D03*
X168299Y1879850D03*
X159054Y1881800D03*
X159173Y1935972D03*
X148499Y1977250D03*
X163500Y1987500D03*
X189499Y4550D03*
Y39150D03*
X183499Y45550D03*
X168499Y65550D03*
X169999Y103050D03*
X176499Y140050D03*
X177899Y199250D03*
X185999Y250550D03*
X181299Y267350D03*
X187199Y359050D03*
X181599Y396250D03*
X168999Y413050D03*
X188499Y413550D03*
X179999Y442550D03*
X179649Y438550D03*
X183999D03*
Y442550D03*
Y447050D03*
X179999D03*
X171300Y476700D03*
X187499Y531613D03*
Y536113D03*
X188999Y541113D03*
Y549613D03*
Y545613D03*
X181999Y624050D03*
Y609550D03*
Y641550D03*
X182599Y688350D03*
X171999Y672450D03*
X170799Y689150D03*
X178899Y765250D03*
X172599Y774250D03*
X168499Y846713D03*
X173899Y846550D03*
X172099Y877450D03*
X169299Y956350D03*
X171499Y998650D03*
X169299Y1067150D03*
X171599Y1139950D03*
X180400Y1202800D03*
X181700Y1219900D03*
X179800Y1244100D03*
X179500Y1262000D03*
X175823Y1297070D03*
X179999Y1301550D03*
Y1292550D03*
X175499D03*
X179999Y1296613D03*
X175499Y1302113D03*
X179999Y1306050D03*
X175499Y1306113D03*
X178200Y1393400D03*
X180599Y1424050D03*
X180000Y1439500D03*
X176599Y1447450D03*
X172299Y1465850D03*
X181500Y1479000D03*
X176299Y1500150D03*
X180299Y1626550D03*
X180000Y1619600D03*
X180299Y1634550D03*
X179733Y1630590D03*
X181900Y1675300D03*
X180701Y1716050D03*
X179701Y1724550D03*
X172499Y1714050D03*
X180000Y1731000D03*
X170499Y1731050D03*
X172499Y1726613D03*
X185999Y1746050D03*
X182299Y1801350D03*
X173899Y1813250D03*
X177599Y1866750D03*
X168499Y1855550D03*
X181099Y1885850D03*
X168699Y1957150D03*
X183999Y1968150D03*
X188199Y1978250D03*
X183000Y1987500D03*
X206999Y5050D03*
X197999Y39900D03*
X193999D03*
X208499Y45650D03*
X199999Y46050D03*
X194499Y44050D03*
X191999Y68050D03*
X192499Y57550D03*
X206899Y171650D03*
X190199Y178650D03*
X191999Y221550D03*
X203499Y250550D03*
X201199Y266750D03*
X209199Y365050D03*
X209499Y412550D03*
X209999Y426150D03*
X194999Y490050D03*
X190499Y487550D03*
X191199Y491550D03*
X205300Y508100D03*
X190499Y507513D03*
X193499Y541113D03*
Y549613D03*
X193999Y545550D03*
X206499Y623550D03*
Y609050D03*
X207300Y639400D03*
X199199Y659150D03*
X190399Y689050D03*
X209500Y759000D03*
X208799Y766750D03*
X190699Y778350D03*
X197099Y795050D03*
X208299Y805350D03*
X202900Y811900D03*
X198199Y805950D03*
X204496Y846111D03*
X204649Y838050D03*
X208999D03*
X209000Y846113D03*
X204649Y842113D03*
X208986D03*
X198499Y884113D03*
X204699Y929450D03*
X206699Y953050D03*
X203999Y943350D03*
X205999Y978250D03*
X206299Y990250D03*
X207299Y1008150D03*
X202100Y1028100D03*
X199499Y1093850D03*
X209900Y1093600D03*
X208199Y1145850D03*
X210199Y1173450D03*
X204199Y1163850D03*
X201600Y1205900D03*
X196499Y1215550D03*
Y1196550D03*
X196399Y1236650D03*
X196499Y1224550D03*
X195499Y1251050D03*
X202199Y1276850D03*
X195499Y1279050D03*
Y1270050D03*
X202899Y1291450D03*
X207699Y1337950D03*
X195500Y1352500D03*
X208049Y1385550D03*
X203199Y1393250D03*
X204699Y1418350D03*
X201000Y1408500D03*
X194200Y1457900D03*
X204999Y1472650D03*
X208999Y1491250D03*
X202399Y1500750D03*
X195700Y1619100D03*
X195600Y1623700D03*
X209200Y1624000D03*
X200600Y1663600D03*
X199900Y1670600D03*
X193499Y1674050D03*
X197600Y1694900D03*
X204400Y1688200D03*
X209901Y1691850D03*
X201801Y1701450D03*
X195001Y1708150D03*
X205200Y1708000D03*
X195500Y1717000D03*
X195000Y1725500D03*
X206900Y1726700D03*
X199699Y1761450D03*
X205199Y1801950D03*
X209999Y1825050D03*
X192100Y1813500D03*
X204399Y1855450D03*
X206999Y1867550D03*
X207199Y1892850D03*
X191599Y1891550D03*
X199599Y1879850D03*
X205499Y1968650D03*
X190199Y1957650D03*
X199600Y1974900D03*
X209699Y1978750D03*
X199000Y1987500D03*
X226499Y5050D03*
X225499Y52550D03*
Y46550D03*
Y63550D03*
Y58050D03*
X229099Y161350D03*
X227999Y178050D03*
X227499Y192050D03*
X227999Y187050D03*
Y182550D03*
X210999Y221550D03*
X217999Y250550D03*
X223799Y365350D03*
X217599Y396450D03*
X218499Y474850D03*
X224299Y494650D03*
X220499Y560050D03*
Y545550D03*
Y577550D03*
X224999Y613450D03*
X219999Y632550D03*
Y647050D03*
X226399Y677550D03*
X212999Y677350D03*
X218800Y668700D03*
X224099Y770250D03*
X214799Y774750D03*
X227199Y795050D03*
X217300Y816800D03*
X215999Y887550D03*
X220499D03*
X215499Y883550D03*
X219499Y939613D03*
X214999D03*
X219499Y926613D03*
X214999D03*
X225299Y957650D03*
X213999Y958650D03*
X219499Y948613D03*
Y943813D03*
X214999Y944113D03*
Y948613D03*
X217499Y981050D03*
X216999Y967550D03*
X217499Y998550D03*
X217999Y1012050D03*
X215999Y1039550D03*
X216499Y1053050D03*
X214499Y1154250D03*
X223099Y1182750D03*
X212499Y1184550D03*
Y1212550D03*
X221599Y1237250D03*
X220999Y1224350D03*
X222299Y1251850D03*
X229899Y1250550D03*
X211499Y1258050D03*
Y1239050D03*
X216300Y1274800D03*
X211499Y1267050D03*
X219099Y1325950D03*
X226599Y1340250D03*
X213199Y1350050D03*
X227399Y1363050D03*
X217499Y1387450D03*
X230599Y1400250D03*
X217999Y1408850D03*
X227999Y1421550D03*
X226300Y1447800D03*
X230899Y1437350D03*
X212400Y1433700D03*
X213399Y1500300D03*
X212899Y1535550D03*
X230999D03*
X211999Y1568550D03*
X231499Y1575050D03*
X224499D03*
X217999Y1574550D03*
X211999D03*
X218000Y1614300D03*
X228999Y1637550D03*
X211999Y1653550D03*
X230600Y1670500D03*
X213000Y1672500D03*
X216601Y1684350D03*
X226800Y1684200D03*
X220100Y1691700D03*
X212000Y1701300D03*
X222700Y1710100D03*
X222499Y1743850D03*
X221499Y1760950D03*
X220799Y1791550D03*
X215299Y1813950D03*
X224800Y1867000D03*
X228999Y1856050D03*
X212399Y1885850D03*
X226999Y1941050D03*
X227499Y1971050D03*
X221300Y1971200D03*
X225199Y1978750D03*
X216999Y1987550D03*
X241999Y5050D03*
X247499Y37550D03*
X246999Y46550D03*
Y56050D03*
X247499Y65050D03*
X244499Y136550D03*
Y122050D03*
X244900Y149100D03*
X231999Y178050D03*
Y192050D03*
Y187050D03*
Y182550D03*
X232400Y220700D03*
X249800Y248800D03*
X235399Y263350D03*
X237699Y426050D03*
X232999Y414550D03*
X252499Y415050D03*
X251499Y446050D03*
X231999Y445550D03*
X251999Y462050D03*
X232499Y461550D03*
X244199Y483350D03*
X242099Y511750D03*
X244999Y559550D03*
Y545050D03*
Y577050D03*
X244499Y632050D03*
X246500Y663300D03*
X245000Y647000D03*
X234200Y668300D03*
X245599Y773450D03*
X234299Y773750D03*
X247099Y795050D03*
X233799Y806350D03*
X245399Y823550D03*
X244099Y857450D03*
X252399Y838250D03*
X245199Y878050D03*
X232399Y886550D03*
X252899Y886350D03*
X245399Y907450D03*
X243899Y923650D03*
X242199Y938750D03*
X252499Y948850D03*
X244199Y973250D03*
X232299Y981950D03*
X233499Y966050D03*
X245899Y995250D03*
X233999Y997050D03*
Y1012550D03*
X232499Y1038050D03*
X249499Y1104150D03*
X232599Y1195750D03*
X251999Y1184550D03*
X242199Y1210050D03*
X242599Y1198350D03*
X247899Y1208650D03*
X234299Y1232650D03*
X250900Y1248500D03*
X242900Y1263000D03*
X232799Y1276150D03*
X241399Y1303250D03*
X239099Y1314150D03*
X252399Y1326350D03*
X245999Y1339050D03*
Y1358050D03*
X234300Y1375700D03*
X246499Y1370050D03*
X249800Y1388400D03*
X244999Y1412550D03*
X245499Y1424550D03*
X238899Y1453750D03*
X248000Y1482000D03*
X250199Y1473550D03*
X247500Y1499000D03*
X236999Y1535550D03*
X238300Y1575100D03*
X246200Y1617600D03*
X239400Y1624300D03*
X242999Y1658050D03*
X237400Y1663800D03*
X235499Y1697050D03*
X249199Y1743150D03*
X237999Y1730550D03*
X244999Y1755050D03*
X252199Y1793050D03*
X238699Y1801850D03*
X241199Y1867150D03*
X244700Y1878700D03*
X241255Y1896055D03*
X238999Y1970550D03*
X232999Y1971050D03*
X240900Y1979000D03*
X236500Y1987500D03*
X261499Y4550D03*
X253999Y48050D03*
X264999Y55350D03*
X261299Y75950D03*
X258699Y104550D03*
X265299Y96250D03*
X262299Y164050D03*
X262699Y208550D03*
X271999Y216050D03*
X265999Y245050D03*
X267498Y305114D03*
Y300114D03*
Y295114D03*
Y310114D03*
X258999Y396650D03*
X266699Y425050D03*
X269999Y415050D03*
X272499Y445050D03*
X266199Y472350D03*
X272999Y461050D03*
X257499Y498050D03*
Y512550D03*
Y530050D03*
X256499Y577050D03*
Y591550D03*
Y609050D03*
X269499Y616550D03*
X257199Y640050D03*
X269499Y631050D03*
Y648550D03*
X268499Y701550D03*
Y706550D03*
Y716550D03*
Y711550D03*
X268099Y795450D03*
X254699Y807650D03*
X264499Y829050D03*
X264999Y842550D03*
Y858450D03*
X265799Y901850D03*
X256199Y916250D03*
X254899Y929250D03*
X253499Y938050D03*
X269599Y923950D03*
X267199Y935350D03*
X264799Y946850D03*
X263299Y959350D03*
X272999Y981050D03*
Y965550D03*
X256499Y967050D03*
X262499Y995850D03*
X254499Y984550D03*
X258999Y1011550D03*
X269999Y1037050D03*
X253499Y1038550D03*
X269999Y1052550D03*
X253999Y1052050D03*
X272999Y1102850D03*
X262499Y1129150D03*
X260349Y1139200D03*
X272499Y1153050D03*
X268499D03*
X263999D03*
X259999Y1152992D03*
X271999Y1161550D03*
X267999D03*
X263499D03*
X259499D03*
X272999Y1214150D03*
X261199Y1227950D03*
X264800Y1261300D03*
X254899Y1289950D03*
X264799Y1313850D03*
X265299Y1339650D03*
X263699Y1359550D03*
X265499Y1376950D03*
X258999Y1396950D03*
X270599Y1408550D03*
X259299Y1438750D03*
X268499Y1453550D03*
X260999Y1503550D03*
X266999Y1512550D03*
X267349Y1518150D03*
Y1522550D03*
Y1527172D03*
X265700Y1635100D03*
X258700Y1645100D03*
X270999Y1660550D03*
X253999Y1676550D03*
X273499Y1694050D03*
X255699Y1722550D03*
X256499Y1710050D03*
X263499Y1734550D03*
X270599Y1748950D03*
X259499Y1760650D03*
X270599Y1801450D03*
X253899Y1813250D03*
X261499Y1825050D03*
X255999Y1855950D03*
X270299Y1867250D03*
X266999Y1915550D03*
Y1920050D03*
Y1924550D03*
Y1929050D03*
Y1933550D03*
X254500Y1987500D03*
X272000D03*
X278999Y5050D03*
X292999Y4550D03*
X294100Y28000D03*
X289499Y39050D03*
X286603Y34928D03*
X289999Y72550D03*
X290999Y67550D03*
X288499Y76550D03*
X289499Y80550D03*
X283599Y106250D03*
X274700Y131500D03*
X280999Y120050D03*
Y152050D03*
X290999Y216050D03*
X283499Y245050D03*
X279998Y304114D03*
Y299614D03*
Y295114D03*
Y308614D03*
X277799Y338599D03*
X293998Y361114D03*
Y356614D03*
Y352114D03*
X289998Y361114D03*
Y356614D03*
Y352114D03*
X276299Y376050D03*
X289399Y395750D03*
X284499Y415050D03*
X291599Y446150D03*
X286999Y462050D03*
X281999Y497550D03*
X292999Y483550D03*
X281999Y512050D03*
Y529550D03*
X277999Y545350D03*
X280999Y576550D03*
Y591050D03*
Y608550D03*
X293999Y616050D03*
Y630550D03*
Y648050D03*
X280999Y701550D03*
Y705550D03*
Y717550D03*
X280433Y713590D03*
X294999Y767050D03*
X290999D03*
X294999Y762550D03*
Y758050D03*
X290999Y762550D03*
Y758050D03*
X287799Y794850D03*
X275299Y806350D03*
X288899Y820550D03*
X280999Y827550D03*
X283599Y857450D03*
X293899Y843850D03*
X280999Y843050D03*
Y870050D03*
X281499Y883550D03*
X274299Y912950D03*
X287299Y901050D03*
X281099Y943550D03*
X278799Y956150D03*
X290099Y948650D03*
X289399Y963350D03*
X277599Y975250D03*
X288099Y971250D03*
X285399Y982950D03*
X294699Y989550D03*
X287099Y1000150D03*
X274999Y996550D03*
X289699Y1021750D03*
X275099Y1024750D03*
X274999Y1012050D03*
X287099Y1035050D03*
X282999Y1099550D03*
X274900Y1115600D03*
X290699Y1122650D03*
X283499Y1113050D03*
X276299Y1134550D03*
X283299Y1144850D03*
X291399Y1174150D03*
X279799Y1191750D03*
X286599Y1203750D03*
X283799Y1249250D03*
X274299Y1276450D03*
X281099Y1302850D03*
X286799Y1326450D03*
X286499Y1364050D03*
Y1345050D03*
X278799Y1386250D03*
X285499Y1399550D03*
X278000Y1422000D03*
X285499Y1418550D03*
Y1427550D03*
X286600Y1449700D03*
X279499Y1510550D03*
X286700Y1516100D03*
X279499Y1515050D03*
X279075Y1525957D03*
X278567Y1529925D03*
X293998Y1573614D03*
Y1569114D03*
X289998Y1573614D03*
Y1569114D03*
X293998Y1578114D03*
X289998D03*
X278499Y1621550D03*
X289000Y1641800D03*
X284300Y1676900D03*
X291099Y1707450D03*
X280499Y1718550D03*
X285499Y1742550D03*
X290699Y1760750D03*
X286599Y1791850D03*
X284299Y1811150D03*
X295299Y1870250D03*
X283999Y1856050D03*
X293999Y1933050D03*
X281999Y1918550D03*
Y1923550D03*
Y1928550D03*
X293999Y1971050D03*
Y1966550D03*
Y1962050D03*
X289499Y1961550D03*
Y1966550D03*
Y1971050D03*
X291499Y1987550D03*
X310499Y5050D03*
X304500Y44500D03*
X303300Y39500D03*
X308700Y39800D03*
X308800Y46400D03*
X306999Y55450D03*
X311299D03*
X315799Y55350D03*
X308499Y72550D03*
X303999Y74050D03*
X307999Y78550D03*
X306100Y126500D03*
X307199Y205550D03*
X310499Y216550D03*
X297999Y245050D03*
X313199Y270350D03*
X313000Y313900D03*
X305998Y352114D03*
X299899Y376650D03*
X310999Y396250D03*
X300899Y431850D03*
X303999Y415550D03*
X306100Y462000D03*
X312499Y484050D03*
X298599Y501250D03*
X309399Y513450D03*
X297599Y519350D03*
X307499Y555550D03*
Y541050D03*
X297499Y551050D03*
X296199Y568550D03*
X307499Y573050D03*
X302899Y607950D03*
X307499Y661550D03*
Y647050D03*
X297699Y681850D03*
X307499Y679050D03*
X308899Y705150D03*
X298399Y703450D03*
X296399Y716950D03*
X306999Y758050D03*
X314499Y754550D03*
X307999Y803150D03*
X307899Y794550D03*
X300199Y835250D03*
X304899Y856150D03*
X313499Y847850D03*
X315199Y869450D03*
X297499Y868550D03*
X302499Y899050D03*
X297499Y884050D03*
X302199Y914650D03*
X315199Y925950D03*
X310699Y943550D03*
X299399Y965950D03*
X298099Y977250D03*
X307999Y970650D03*
X306699Y981250D03*
X304399Y997550D03*
X298399Y1008150D03*
X306399Y1020750D03*
X303699Y1038050D03*
X299999Y1052350D03*
X304699Y1057050D03*
X312299Y1093550D03*
X299499Y1098050D03*
Y1113550D03*
X316499Y1124550D03*
X307999Y1142050D03*
X304499Y1156650D03*
X313499Y1170150D03*
X300699Y1185150D03*
X315408Y1202663D03*
X311999Y1213850D03*
X300699Y1227350D03*
X310299Y1240050D03*
X304699Y1265850D03*
X312499Y1280350D03*
X295399Y1292950D03*
X300499Y1305350D03*
X311500Y1316300D03*
X297899Y1336150D03*
X298099Y1357250D03*
X311900Y1344900D03*
X301699Y1377950D03*
X312900Y1366900D03*
X301699Y1395750D03*
X313600Y1391300D03*
X303499Y1411250D03*
X312100Y1420700D03*
X300899Y1433350D03*
X313600Y1442700D03*
X304699Y1457550D03*
X312800Y1467400D03*
X296599Y1497150D03*
X312000Y1514600D03*
X305998Y1569114D03*
X307000Y1619600D03*
X302399Y1662950D03*
X299999Y1696050D03*
X303999Y1722050D03*
X297099Y1733850D03*
X303499Y1753550D03*
X303999Y1800850D03*
X315499Y1812250D03*
X298999Y1855950D03*
X313599Y1870250D03*
X308099Y1880550D03*
X313599Y1889250D03*
X314099Y1901250D03*
X305999Y1913050D03*
X306999Y1932550D03*
X302499D03*
X298499D03*
X302499Y1922050D03*
X296858Y1956228D03*
X305999Y1964050D03*
Y1969550D03*
X311500Y1987500D03*
X329999Y5050D03*
X332200Y94200D03*
X321799Y173950D03*
X317499Y192950D03*
X331499Y193250D03*
X325499Y249450D03*
X337499Y282550D03*
X316999Y312576D03*
X321748Y343299D03*
X328799Y372350D03*
X336099Y417550D03*
X322099Y426850D03*
X324999Y414550D03*
X328599Y442250D03*
X327900Y463200D03*
X333499Y483050D03*
X329999Y510450D03*
X321999Y533150D03*
X331999Y555050D03*
Y540550D03*
X321999Y550550D03*
X321299Y565250D03*
X320799Y582050D03*
X331999Y572550D03*
X328599Y602450D03*
X328499Y635650D03*
X317999Y627850D03*
X331999Y661050D03*
Y646550D03*
Y678550D03*
X324599Y696150D03*
X330799Y712450D03*
X318999Y814350D03*
X325599Y823950D03*
X330299Y871850D03*
X323799Y859850D03*
X321099Y899650D03*
X323099Y885050D03*
X322099Y913650D03*
X331099Y923650D03*
X328099Y937250D03*
X323499Y956950D03*
X329799Y970650D03*
X333099Y983450D03*
X320999Y997250D03*
X331299Y1017150D03*
X321299Y1012450D03*
Y1024750D03*
X331599Y1028750D03*
X329599Y1040750D03*
X318299Y1038750D03*
X329599Y1057050D03*
X319999Y1066950D03*
X317699Y1054650D03*
X329299Y1098550D03*
X326599Y1112350D03*
X332999Y1123050D03*
X323999Y1153250D03*
X332999Y1138550D03*
X317999Y1137550D03*
X329799Y1182750D03*
X328999Y1200550D03*
X326649Y1227850D03*
Y1218850D03*
X327999Y1255050D03*
X333349Y1270500D03*
Y1288900D03*
Y1307000D03*
Y1332800D03*
Y1363500D03*
Y1393100D03*
Y1429500D03*
Y1481900D03*
X332500Y1519700D03*
X337199Y1636350D03*
X320299Y1642950D03*
X316799Y1657450D03*
X335767Y1662735D03*
X318499Y1675550D03*
X334399Y1691650D03*
X329999Y1716950D03*
X320999Y1706050D03*
X321999Y1733050D03*
X326301Y1766030D03*
X321499Y1772550D03*
X327299Y1791850D03*
X322299Y1802150D03*
X334999Y1797050D03*
X337499Y1855950D03*
X316999D03*
X336799Y1869950D03*
X326399Y1876250D03*
X336799Y1888950D03*
X326899Y1907250D03*
X326399Y1895250D03*
X336799Y1897950D03*
X335799Y1916450D03*
X326799Y1977050D03*
X329999Y1987550D03*
X345499Y5050D03*
X356499Y113050D03*
X351999D03*
X347499D03*
X355999Y100550D03*
X350999D03*
X345999D03*
X354099Y175350D03*
X343399Y161350D03*
X343999Y190050D03*
X343799Y204550D03*
X355499Y219050D03*
X337999D03*
X355999Y242750D03*
X343499Y253550D03*
X347699Y269050D03*
X354999Y282550D03*
X347399Y301950D03*
X339399Y358050D03*
X357999Y359050D03*
X354099Y373050D03*
X338399Y395650D03*
X338899Y433850D03*
X354699Y426650D03*
X356399Y451750D03*
X351399Y470750D03*
X340799Y512050D03*
X358399Y498650D03*
X341399Y535850D03*
X357399Y521250D03*
Y530550D03*
X341399Y558950D03*
X357399Y543850D03*
X357999Y559450D03*
X340299Y586550D03*
X342199Y613050D03*
X342099Y646350D03*
X341899Y664950D03*
X342599Y678850D03*
X345399Y698950D03*
X357699Y707750D03*
X341399Y715050D03*
X355999Y752850D03*
X353999Y787750D03*
X347699Y773450D03*
X338099Y811650D03*
X338599Y821650D03*
Y840450D03*
X340099Y887350D03*
X338399Y901050D03*
X340099Y910350D03*
X340399Y931250D03*
X340099Y952850D03*
X339599Y1081550D03*
X344399Y1338150D03*
X343599Y1360050D03*
X344099Y1393750D03*
Y1421150D03*
Y1449550D03*
X351899Y1570850D03*
X344500Y1583600D03*
X350600Y1610900D03*
X349099Y1634550D03*
X351099Y1691150D03*
X352000Y1700400D03*
X343899Y1752650D03*
X357999Y1796050D03*
X355699Y1810750D03*
X351999Y1855450D03*
X348999Y1879050D03*
X349499Y1910050D03*
X348999Y1898050D03*
X347999Y1925550D03*
X348499Y1956550D03*
X347999Y1944550D03*
X347699Y1972250D03*
X345499Y1987550D03*
X364999Y4550D03*
X371999Y15550D03*
X376499D03*
X369999Y23550D03*
Y19050D03*
X376999Y65550D03*
Y70050D03*
X360999Y113050D03*
Y100550D03*
X363999Y136050D03*
Y121550D03*
Y153550D03*
X362999Y190050D03*
X369999Y219050D03*
X362499Y253550D03*
X369499Y282550D03*
X359399Y307250D03*
X368299Y386350D03*
X359399Y576050D03*
Y599650D03*
X360399Y615550D03*
X359699Y627550D03*
X358899Y657150D03*
X359399Y669450D03*
X359199Y690650D03*
X377499Y1182050D03*
Y1210050D03*
Y1201050D03*
X376499Y1236550D03*
Y1255550D03*
Y1264550D03*
X376599Y1293950D03*
X375599Y1323350D03*
X374499Y1347550D03*
Y1375550D03*
Y1366550D03*
X373499Y1402050D03*
Y1421050D03*
X376299Y1437650D03*
X373499Y1430050D03*
X373099Y1456550D03*
X374799Y1491250D03*
X374099Y1554550D03*
X376099Y1572850D03*
X375099Y1608250D03*
X377700Y1629000D03*
X374999Y1656750D03*
X377099Y1696350D03*
X359499Y1736850D03*
X376799Y1734050D03*
X376499Y1775550D03*
X369499Y1855950D03*
X359999Y1878550D03*
X369799Y1880050D03*
X359999Y1897550D03*
Y1906550D03*
X369999Y1901950D03*
X358999Y1925050D03*
X369199Y1919750D03*
X367299Y1956950D03*
X367999Y1940250D03*
X367299Y1972950D03*
X364999Y1987050D03*
X382499Y5050D03*
X395999Y5550D03*
X380999Y15550D03*
X382499Y20050D03*
X381499Y65550D03*
Y70050D03*
X389599Y90950D03*
X380599Y103550D03*
X381299Y136750D03*
X400499Y134050D03*
Y119550D03*
Y151550D03*
X389299Y161650D03*
X382499Y190550D03*
X387599Y220150D03*
X385999Y207250D03*
X381999Y254050D03*
X382999Y276650D03*
X386899Y299250D03*
X383299Y310250D03*
X386599Y348450D03*
X394899Y357750D03*
X380599Y381050D03*
X380099Y1709650D03*
X393499Y1759550D03*
X393999Y1784550D03*
X387899Y1802850D03*
X391499Y1855950D03*
X389499Y1885050D03*
Y1913050D03*
Y1904050D03*
X388499Y1932950D03*
Y1950550D03*
X385099Y1975950D03*
X399299Y1976750D03*
X388499Y1959550D03*
X382499Y1987550D03*
X413499Y6050D03*
X416999Y25050D03*
X417499Y46550D03*
X416999Y63550D03*
X417499Y79050D03*
Y93550D03*
Y108050D03*
Y125550D03*
X416999Y145050D03*
Y164050D03*
X417999Y185050D03*
X412999Y275550D03*
Y307550D03*
Y290050D03*
X422199Y363350D03*
X420199Y391350D03*
X415099Y422550D03*
X410799Y431150D03*
X419599Y458550D03*
X415999Y518550D03*
X420199Y638550D03*
X418799Y877050D03*
Y896050D03*
X409499Y1102550D03*
X419999Y1115550D03*
X415499Y1161550D03*
X416099Y1183550D03*
X415499Y1176050D03*
X419499Y1234050D03*
Y1219550D03*
X420099Y1241550D03*
X416699Y1342650D03*
X416199Y1367550D03*
X414799Y1532350D03*
X418299Y1561250D03*
X415999Y1603250D03*
X416199Y1625250D03*
X414799Y1653750D03*
X414399Y1678350D03*
X414499Y1707250D03*
X410757Y1772872D03*
X417799Y1790850D03*
X414499Y1810450D03*
X406999Y1855950D03*
X421399Y1888050D03*
X406499Y1893050D03*
Y1874050D03*
X421399Y1907050D03*
X406999Y1905050D03*
X420399Y1934550D03*
X421399Y1916050D03*
X405499Y1920550D03*
X420399Y1953550D03*
X405999Y1951550D03*
X405499Y1939550D03*
X420399Y1962550D03*
X420799Y1977250D03*
X420500Y1987000D03*
X403500D03*
X432999Y6050D03*
X436499Y31350D03*
Y50350D03*
X437499Y71350D03*
X441799Y102450D03*
Y121450D03*
X442799Y142450D03*
X430499Y217050D03*
X423799Y259750D03*
X437499Y275050D03*
Y307050D03*
Y289550D03*
X422499Y348150D03*
X438999Y381550D03*
X426599Y415350D03*
X443199Y440850D03*
X440099Y459250D03*
X431099Y479350D03*
X435499Y519050D03*
X430099Y551450D03*
X427999Y580050D03*
Y565550D03*
Y597550D03*
X427499Y624550D03*
X437299Y744650D03*
X435299Y763150D03*
X424999Y766550D03*
X435299Y777650D03*
X422999Y785050D03*
X434799Y814650D03*
X435299Y795150D03*
X422999Y799550D03*
X434799Y833650D03*
X422999Y817050D03*
X422499Y855550D03*
Y836550D03*
X442599Y905650D03*
Y924650D03*
X423299Y994050D03*
Y1013050D03*
X424299Y1034050D03*
X432599Y1064550D03*
X433599Y1085550D03*
X428999Y1102550D03*
X439499Y1115550D03*
X436999Y1128050D03*
X437599Y1150050D03*
X436999Y1142550D03*
X443199Y1224250D03*
Y1238750D03*
X424999Y1278550D03*
Y1259550D03*
X425499Y1290550D03*
X428499Y1325350D03*
X434499Y1360250D03*
X422299Y1394950D03*
X441499Y1399550D03*
X426799Y1416050D03*
X441499Y1414050D03*
X423299Y1430350D03*
X425799Y1447950D03*
X441499Y1431550D03*
X427099Y1469150D03*
X424299Y1541350D03*
X439599Y1552150D03*
X434500Y1579500D03*
X432499Y1617550D03*
X431999Y1605550D03*
X425499Y1635050D03*
X432400Y1680100D03*
X427499Y1662050D03*
X428600Y1691200D03*
X435300Y1715300D03*
X429499Y1748050D03*
X441499Y1758050D03*
X436799Y1772550D03*
X422999Y1778550D03*
X426499Y1855450D03*
X434299Y1876050D03*
Y1904050D03*
Y1895050D03*
X433299Y1922550D03*
Y1950550D03*
Y1941550D03*
X436299Y1977250D03*
X438999Y1987550D03*
X448499Y6050D03*
X445799Y165650D03*
Y184650D03*
X446799Y205650D03*
X449999Y217050D03*
X448999Y255550D03*
X444499Y283050D03*
X463999Y283550D03*
X443499Y354050D03*
X464499Y353050D03*
X458499Y382050D03*
X450300Y404200D03*
X453999Y417550D03*
X454999Y438550D03*
X454499Y472550D03*
Y458050D03*
Y490050D03*
X456499Y518050D03*
X453999Y509550D03*
X452499Y579550D03*
Y565050D03*
Y597050D03*
X463999Y659550D03*
X450399Y672750D03*
X444799Y687350D03*
X463999Y674050D03*
Y691550D03*
X451099Y711650D03*
X452099Y762450D03*
Y781450D03*
X453399Y807950D03*
Y826950D03*
X462999Y865050D03*
Y884050D03*
X464499Y896050D03*
X462499Y914550D03*
Y929050D03*
X443599Y945650D03*
X462499Y946550D03*
X461999Y966050D03*
Y985050D03*
X462499Y1043850D03*
Y1062850D03*
X463499Y1083850D03*
X463999Y1102050D03*
X444499Y1102550D03*
X454999Y1115550D03*
X453499Y1140550D03*
X454499Y1161550D03*
X443799Y1246250D03*
Y1274250D03*
Y1265250D03*
X448099Y1341250D03*
X444899Y1377950D03*
X464199Y1401450D03*
X459999Y1424050D03*
X456399Y1445950D03*
X459699Y1468050D03*
X445099Y1464250D03*
X444299Y1532650D03*
X461399Y1541650D03*
X452199Y1550650D03*
X449199Y1579050D03*
X443799Y1612250D03*
X460199Y1632850D03*
X449599Y1656950D03*
X448399Y1699450D03*
X447699Y1682850D03*
X458499Y1742050D03*
X463999Y1772050D03*
X445499Y1792550D03*
X448099Y1809450D03*
X443999Y1855950D03*
X460299Y1892350D03*
X446999Y1880050D03*
X460299Y1911350D03*
X446999Y1908050D03*
Y1899050D03*
X460299Y1920350D03*
X445999Y1926550D03*
X459299Y1938850D03*
X445999Y1954550D03*
Y1945550D03*
X459299Y1966850D03*
Y1957850D03*
X455799Y1976750D03*
X456500Y1987500D03*
X467999Y5550D03*
X485499Y6050D03*
X465799Y24750D03*
Y43750D03*
X466799Y64750D03*
X470399Y84550D03*
Y103550D03*
X471399Y124550D03*
X473099Y141050D03*
X483599Y179350D03*
X473099Y160050D03*
X474099Y181050D03*
X472999Y214550D03*
X469999Y254550D03*
X481499Y283550D03*
X466399Y304950D03*
X479299Y297250D03*
X483499Y353050D03*
X485000Y373200D03*
X484900Y394700D03*
X468799Y414250D03*
X472499Y458050D03*
X471499Y493950D03*
X485299Y534550D03*
X479999Y581050D03*
Y566550D03*
Y598550D03*
X472999Y736550D03*
X467699Y772750D03*
X468699Y788350D03*
X479599Y847550D03*
X475699Y880450D03*
X483499Y1064850D03*
X484499Y1085850D03*
X481499Y1102550D03*
X474499Y1115050D03*
X473099Y1144550D03*
X474099Y1165550D03*
X465499Y1265550D03*
Y1284550D03*
Y1293550D03*
X468999Y1323950D03*
X473999Y1342450D03*
X468699Y1362850D03*
X485599Y1367550D03*
X466699Y1378150D03*
X481499Y1402550D03*
Y1417050D03*
X482599Y1449950D03*
X478299Y1464850D03*
X466999Y1530650D03*
X474299Y1544750D03*
X472299Y1572050D03*
X484200Y1579900D03*
X465999Y1603450D03*
X472499Y1611550D03*
X484999Y1636550D03*
X472499Y1620550D03*
X483599Y1662550D03*
X467999Y1668050D03*
X485599Y1694850D03*
X467999Y1687050D03*
Y1696050D03*
X468499Y1712550D03*
X480999Y1756050D03*
X484999Y1779050D03*
X472699Y1792150D03*
X481299Y1811150D03*
X480499Y1855450D03*
X464999D03*
X476199Y1877450D03*
Y1905450D03*
Y1896450D03*
X475199Y1923950D03*
Y1951950D03*
Y1942950D03*
X473299Y1977250D03*
X476000Y1987000D03*
X498999Y6050D03*
X499999Y25550D03*
X500499Y47050D03*
X499999Y64050D03*
X500499Y79550D03*
Y94050D03*
Y108550D03*
Y126050D03*
X499999Y145550D03*
Y164550D03*
X504199Y193250D03*
X502899Y217150D03*
X488999Y254550D03*
X495999Y283550D03*
X502999Y353550D03*
X490999Y412550D03*
X503699Y419250D03*
X490999Y427050D03*
Y444550D03*
X498399Y470050D03*
X490499Y464050D03*
Y483050D03*
X491499Y504050D03*
X504499Y580550D03*
Y566050D03*
Y598050D03*
X488499Y659050D03*
Y673550D03*
Y691050D03*
X506599Y711650D03*
X487299Y716950D03*
X490299Y734550D03*
X489599Y752450D03*
X495999Y795050D03*
X493999Y813550D03*
Y828050D03*
Y845550D03*
X493499Y865050D03*
Y884050D03*
X485799Y920050D03*
Y901050D03*
X486799Y941050D03*
X493099Y996350D03*
X494099Y1017350D03*
X501499Y1102550D03*
X491999Y1115550D03*
X504399Y1132250D03*
X505399Y1153250D03*
X486499Y1210550D03*
Y1196050D03*
X506599Y1202350D03*
Y1216850D03*
X487099Y1218050D03*
X498299Y1323350D03*
X499199Y1350550D03*
X498899Y1386450D03*
Y1408350D03*
X500899Y1434350D03*
X505899Y1466250D03*
X488299Y1531050D03*
X499699Y1538950D03*
X502199Y1566250D03*
X487099Y1606250D03*
X501399Y1634550D03*
X502899Y1709650D03*
X496999Y1799550D03*
X499999Y1854950D03*
X505799Y1893050D03*
X492999Y1878050D03*
X505799Y1912050D03*
X493499Y1909050D03*
X492999Y1897050D03*
X505799Y1921050D03*
X491999Y1924550D03*
X504799Y1939550D03*
X492499Y1955550D03*
X491999Y1943550D03*
X504799Y1967550D03*
Y1958550D03*
X493799Y1977250D03*
X492500Y1987500D03*
X516499Y6550D03*
X522899Y45350D03*
Y64350D03*
X523899Y85350D03*
X520299Y122450D03*
Y141450D03*
X521299Y162450D03*
X508499Y255050D03*
X525999D03*
X515499Y284050D03*
X516899Y306950D03*
X520499Y353550D03*
X509999Y382550D03*
X518999Y416550D03*
X511299Y449150D03*
X519499Y471550D03*
Y489050D03*
X508699Y498950D03*
X518999Y508550D03*
X514499Y546050D03*
X509999Y640550D03*
Y655050D03*
Y672550D03*
X527499Y747150D03*
X525499Y772450D03*
X511199Y782050D03*
X512899Y823550D03*
X526499Y851150D03*
X512899Y842550D03*
X510899Y868150D03*
X522499Y876050D03*
X521999Y895550D03*
X506899Y919950D03*
Y900950D03*
X521999Y914550D03*
X516499Y957050D03*
X514499Y975550D03*
Y990050D03*
Y1007550D03*
X513999Y1046050D03*
Y1027050D03*
X518999Y1103050D03*
X511999Y1115550D03*
X527499Y1181550D03*
X527999Y1212550D03*
X527499Y1200550D03*
X507199Y1224350D03*
X525999Y1231050D03*
X507199Y1252350D03*
Y1243350D03*
X525999Y1245550D03*
X527499Y1278150D03*
X525999Y1263050D03*
X518499Y1346950D03*
X523499Y1360050D03*
X508599Y1370550D03*
X523499Y1379050D03*
X523999Y1391050D03*
X516999Y1418050D03*
Y1437050D03*
X517499Y1449050D03*
X518899Y1530150D03*
X510100Y1579800D03*
X508199Y1610450D03*
X518499Y1643950D03*
X509199Y1660550D03*
X507399Y1683350D03*
X522300Y1739200D03*
X508200Y1758200D03*
X515499Y1779050D03*
X526499Y1801150D03*
X514199Y1815750D03*
X517499Y1855450D03*
X519399Y1876750D03*
Y1904750D03*
Y1895750D03*
X518399Y1923250D03*
Y1951250D03*
Y1942250D03*
X509299Y1977250D03*
X511999Y1987550D03*
X535999Y6550D03*
X541499Y25050D03*
X541999Y46550D03*
X541499Y63550D03*
X541999Y79050D03*
Y93550D03*
Y108050D03*
Y125550D03*
X541499Y145050D03*
Y164050D03*
X528799Y199950D03*
X542499Y185050D03*
X533499Y217550D03*
X540499Y255050D03*
X536499Y283050D03*
X544799Y293950D03*
X540099Y306550D03*
X548100Y362200D03*
X530999Y381550D03*
X538799Y445050D03*
X539799Y466050D03*
X539299Y485550D03*
X535499Y545050D03*
X538999Y562050D03*
X534499Y640050D03*
Y654550D03*
Y672050D03*
X547999Y728550D03*
Y743050D03*
Y760550D03*
X547499Y780050D03*
X534499Y805950D03*
X547499Y799050D03*
X541399Y854450D03*
Y873450D03*
X539299Y935850D03*
X540299Y956850D03*
X540899Y981450D03*
Y1000450D03*
X541899Y1021450D03*
X534599Y1048550D03*
X535599Y1069550D03*
X538499Y1103050D03*
X548999Y1116050D03*
X529499D03*
X546499Y1180750D03*
Y1195250D03*
X547099Y1202750D03*
Y1230750D03*
Y1221750D03*
X548799Y1252850D03*
Y1267350D03*
X530499Y1297050D03*
X545099Y1355250D03*
X540399Y1382150D03*
X538799Y1409750D03*
X536799Y1436350D03*
X528499Y1460250D03*
X546099Y1467550D03*
X538999Y1528350D03*
X529799Y1555050D03*
X533800Y1575500D03*
X529499Y1616550D03*
X528999Y1604550D03*
X532499Y1635550D03*
X532599Y1655650D03*
X532499Y1669550D03*
Y1688550D03*
X532999Y1700550D03*
X538299Y1721050D03*
X532499Y1763050D03*
X539499Y1788150D03*
X544300Y1784638D03*
X531799Y1818450D03*
X538999Y1855950D03*
X547999Y1892350D03*
X533499Y1884050D03*
X547999Y1911350D03*
X533499Y1912050D03*
Y1903050D03*
X547999Y1920350D03*
X532499Y1930550D03*
X546999Y1938850D03*
X532499Y1949550D03*
X546999Y1966850D03*
Y1957850D03*
X546299Y1977250D03*
X528799Y1976750D03*
X532499Y1958550D03*
X531500Y1987500D03*
X551499Y6550D03*
X568099Y72550D03*
Y91550D03*
X569099Y112550D03*
X562799Y127750D03*
Y146750D03*
X563799Y167750D03*
X565999Y199950D03*
X568499Y217550D03*
X552999D03*
X557999Y322550D03*
Y326550D03*
X558099Y335050D03*
X557933Y331010D03*
X555999Y412550D03*
X556499Y467550D03*
Y485050D03*
X555999Y504550D03*
X558499Y562550D03*
Y616050D03*
X554304Y615840D03*
X554499Y624550D03*
X558699D03*
X554499Y620050D03*
X558709Y620245D03*
X565699Y710650D03*
X549999Y710050D03*
X562999Y898050D03*
X560999Y916550D03*
Y931050D03*
Y948550D03*
X560499Y968050D03*
Y987050D03*
X560999Y999050D03*
X558999Y1017550D03*
Y1032050D03*
X558499Y1069050D03*
X558999Y1049550D03*
X558499Y1088050D03*
X568499Y1101550D03*
X553999Y1103050D03*
X564499Y1116050D03*
X567999Y1187550D03*
Y1215550D03*
Y1206550D03*
X565999Y1234050D03*
Y1248550D03*
X566399Y1273850D03*
X549399Y1274850D03*
X561099Y1301050D03*
X549399Y1293850D03*
Y1302850D03*
X555699Y1322950D03*
X559099Y1343250D03*
X557499Y1424050D03*
Y1443050D03*
Y1452050D03*
X563499Y1486550D03*
Y1492050D03*
Y1497550D03*
Y1503550D03*
X567999Y1549950D03*
X552199Y1576650D03*
X552099Y1601950D03*
X569499Y1610550D03*
X553399Y1624550D03*
X569499Y1619550D03*
X554199Y1651950D03*
X555199Y1674750D03*
X555399Y1689350D03*
X555899Y1706750D03*
X556199Y1727050D03*
X560399Y1792550D03*
X555500Y1802700D03*
X554499Y1855950D03*
X562599Y1893450D03*
Y1874450D03*
Y1902450D03*
X561599Y1920950D03*
Y1948950D03*
Y1939950D03*
X570299Y1976250D03*
X568999Y1987050D03*
X553499D03*
X570999Y6050D03*
X588499Y6550D03*
X587999Y25050D03*
X588499Y46550D03*
X587999Y63550D03*
X588499Y125550D03*
X587999Y145050D03*
Y164050D03*
X588999Y185050D03*
X587999Y217050D03*
X572999Y255050D03*
Y269550D03*
Y287050D03*
X572499Y306550D03*
Y325550D03*
X573499Y346550D03*
X579899Y375750D03*
X577399Y420050D03*
X578399Y441050D03*
X577899Y460550D03*
X576099Y481850D03*
X577099Y502850D03*
X576599Y522350D03*
X579499Y561550D03*
X573499Y658550D03*
Y673050D03*
Y690550D03*
X586299Y711250D03*
X577999Y732050D03*
X575999Y750550D03*
Y765050D03*
Y782550D03*
X575499Y802050D03*
Y821050D03*
X576499Y842050D03*
X578299Y895650D03*
Y914650D03*
X583299Y961450D03*
X570899Y946850D03*
X583299Y980450D03*
X570899Y965850D03*
X571899Y986850D03*
X573499Y1036550D03*
Y1055550D03*
X574499Y1076550D03*
X588499Y1101550D03*
X578999Y1114550D03*
X582699Y1233250D03*
X583299Y1255250D03*
X582699Y1247750D03*
X583299Y1274250D03*
X579299Y1300750D03*
X583299Y1283250D03*
X581999Y1370150D03*
X580999Y1412750D03*
X575699Y1438950D03*
X582999Y1461250D03*
X590599Y1483450D03*
X582299Y1534150D03*
X588099Y1572050D03*
X573400Y1577600D03*
X588000Y1604000D03*
X590799Y1627850D03*
X580799Y1646150D03*
X572999Y1675550D03*
X590599Y1694450D03*
X572999Y1694550D03*
Y1703550D03*
X580299Y1722550D03*
X582599Y1740050D03*
X573999Y1855450D03*
X588899Y1882350D03*
X575999Y1888050D03*
X588899Y1910350D03*
Y1901350D03*
X575999Y1907050D03*
X587899Y1928850D03*
X576499Y1919050D03*
X574999Y1934550D03*
X587899Y1956850D03*
Y1947850D03*
X574999Y1953550D03*
X585799Y1976250D03*
X575499Y1965550D03*
X588499Y1986550D03*
X608499Y6550D03*
X603999Y35350D03*
Y54350D03*
X604999Y75350D03*
X603999Y133750D03*
Y152750D03*
X604999Y173750D03*
X605499Y217550D03*
X599299Y344650D03*
X600299Y365650D03*
X599799Y385150D03*
X607399Y380250D03*
X592999Y407550D03*
Y422050D03*
Y439550D03*
X592499Y459050D03*
Y478050D03*
X593499Y499050D03*
X606499Y584550D03*
X595999Y624050D03*
Y609550D03*
Y641550D03*
X605299Y661750D03*
X609499Y708050D03*
X597999Y690050D03*
X607499Y726550D03*
Y741050D03*
Y758550D03*
X606999Y778050D03*
Y797050D03*
X603499Y904050D03*
X601499Y922550D03*
Y937050D03*
Y954550D03*
X600999Y1002050D03*
X611399Y1026650D03*
X598999Y1020550D03*
X611399Y1045650D03*
X598999Y1035050D03*
X612399Y1066650D03*
X598999Y1052550D03*
X598499Y1072050D03*
X605999Y1102050D03*
X598499Y1091050D03*
X598999Y1114550D03*
X603899Y1157850D03*
X597599Y1196050D03*
X596599Y1215050D03*
X600899Y1238650D03*
X598499Y1280550D03*
Y1261550D03*
X598999Y1292550D03*
X608899Y1305050D03*
X605599Y1326350D03*
X606199Y1338250D03*
X599499Y1351550D03*
X599999Y1382550D03*
X599499Y1370550D03*
X604899Y1407750D03*
X601299Y1447650D03*
X610899Y1496750D03*
X599799Y1544650D03*
X611900Y1577900D03*
X612499Y1615550D03*
X611999Y1603550D03*
X600599Y1645450D03*
X593399Y1668850D03*
X609499Y1675050D03*
Y1692050D03*
X607599Y1716450D03*
X606999Y1745550D03*
X593299Y1760950D03*
X608599Y1810750D03*
X595199Y1820910D03*
X611999Y1855950D03*
X591499D03*
X602799Y1887350D03*
Y1906350D03*
X601799Y1933850D03*
X602799Y1915350D03*
X601799Y1952850D03*
Y1961850D03*
X605299Y1975750D03*
X605999Y1987050D03*
X625999Y7050D03*
X624499Y23050D03*
X624999Y44550D03*
X624499Y61550D03*
X624999Y123550D03*
X624499Y143050D03*
Y162050D03*
X625499Y183050D03*
X623899Y202550D03*
X625499Y217550D03*
X627999Y262550D03*
Y248050D03*
Y280050D03*
X627499Y299550D03*
X628200Y320000D03*
X628499Y339550D03*
X632399Y358750D03*
X620999Y411550D03*
X621999Y432550D03*
X621499Y452050D03*
Y466550D03*
Y484050D03*
X613700Y504600D03*
X625999Y585050D03*
X620499Y623550D03*
Y609050D03*
X631999Y639650D03*
X622999Y672050D03*
Y689550D03*
X629099Y714050D03*
X633499Y750150D03*
X621499Y767150D03*
X621999Y835050D03*
X612999Y854550D03*
X629499Y853050D03*
Y868550D03*
X613499Y868050D03*
X616699Y948250D03*
Y967250D03*
X617699Y988250D03*
X631999Y1001550D03*
X629999Y1020050D03*
Y1034550D03*
Y1052050D03*
X629499Y1071550D03*
Y1090550D03*
X616499Y1115050D03*
X627699Y1143550D03*
X628699Y1164550D03*
X626199Y1183450D03*
X630499Y1243950D03*
X617599Y1246250D03*
X618199Y1268250D03*
X617599Y1260750D03*
X618199Y1296250D03*
Y1287250D03*
X631799Y1322650D03*
X617899Y1360850D03*
X632499Y1347950D03*
X625499Y1383450D03*
X627499Y1406050D03*
X626799Y1432350D03*
X625199Y1489150D03*
X617699Y1530350D03*
X623499Y1564050D03*
X633499Y1615450D03*
X628499Y1636650D03*
X627299Y1659550D03*
X625499Y1725050D03*
X619499Y1803150D03*
X627273Y1793905D03*
X626999Y1800050D03*
X632799Y1820450D03*
X627494Y1829068D03*
X627499Y1855950D03*
X630699Y1872750D03*
Y1891750D03*
Y1900750D03*
X616499Y1913050D03*
Y1894050D03*
X629699Y1919250D03*
X616499Y1922050D03*
X629699Y1947250D03*
Y1938250D03*
X615499Y1940550D03*
X622799Y1976250D03*
X615499Y1959550D03*
Y1968550D03*
X626999Y1987050D03*
X645499Y7050D03*
X651799Y40650D03*
Y59650D03*
X652799Y80650D03*
X649899Y138350D03*
Y157350D03*
X650899Y178350D03*
X642999Y218050D03*
X653999Y286550D03*
X635399Y376250D03*
X643599Y395950D03*
X644599Y416950D03*
X644099Y450950D03*
Y436450D03*
X642499Y525750D03*
X643499Y546750D03*
X642999Y566250D03*
X646999Y584550D03*
X640599Y604650D03*
X645099Y639150D03*
X647499Y657050D03*
Y671550D03*
X648999Y702350D03*
X647499Y689050D03*
X651999Y718350D03*
X647399Y742150D03*
X653099Y803350D03*
X645799Y816650D03*
X641599Y843250D03*
Y862250D03*
X642599Y883250D03*
X639499Y952150D03*
Y971150D03*
X633999Y1103050D03*
X641799Y1137650D03*
X650299Y1153150D03*
X651299Y1174150D03*
X650599Y1182050D03*
X651599Y1203050D03*
X638999Y1267550D03*
Y1286550D03*
Y1295550D03*
X654499Y1354050D03*
Y1373050D03*
X652999Y1403550D03*
Y1418050D03*
Y1435550D03*
X636799Y1461250D03*
X643099Y1541350D03*
X652399Y1575850D03*
X639200Y1576200D03*
X635500Y1603900D03*
X652499Y1618550D03*
Y1609550D03*
X649399Y1644950D03*
X635099Y1691150D03*
X642499Y1709050D03*
X650399Y1771250D03*
X642400Y1800100D03*
X633837Y1807384D03*
X640999Y1815550D03*
X644049Y1810834D03*
X645099Y1877550D03*
X645399Y1906150D03*
X646799Y1926450D03*
X644999Y1934050D03*
Y1953050D03*
X643799Y1976250D03*
X645499Y1965050D03*
X642499Y1987050D03*
X660999Y7050D03*
X674999Y20550D03*
X675499Y42050D03*
Y74550D03*
X674999Y59050D03*
X675499Y89050D03*
Y103550D03*
Y121050D03*
X674999Y140550D03*
Y159550D03*
X675999Y180550D03*
X662499Y218050D03*
X656499Y307050D03*
Y324550D03*
X655999Y344050D03*
X659899Y363250D03*
X666999Y476550D03*
Y491050D03*
Y508550D03*
X666499Y528050D03*
Y547050D03*
X667499Y568050D03*
X674999Y601550D03*
X665999Y623550D03*
X673999Y645150D03*
X665499Y766550D03*
X664999Y786050D03*
Y805050D03*
X665999Y826050D03*
X663999Y844550D03*
Y876550D03*
Y859050D03*
X663499Y896050D03*
Y915050D03*
X664499Y936050D03*
X658999Y959050D03*
X656999Y977550D03*
Y992050D03*
X673999Y1017550D03*
X656999Y1009550D03*
X673999Y1036550D03*
X656499Y1029050D03*
X674699Y1061450D03*
X656499Y1048050D03*
X674699Y1080450D03*
X669499Y1116550D03*
X674999Y1134950D03*
X667199Y1152850D03*
X668199Y1173850D03*
X670199Y1192750D03*
X671199Y1213750D03*
X668699Y1227650D03*
X657099Y1272850D03*
X657799Y1288450D03*
X672999Y1303450D03*
X656399Y1307050D03*
X671999Y1324950D03*
X665699Y1337250D03*
X654999Y1385050D03*
X659699Y1445950D03*
X665699Y1462250D03*
X656099Y1479550D03*
X672399Y1508750D03*
X673699Y1535350D03*
X662099Y1549650D03*
X670699Y1603150D03*
X671399Y1625350D03*
X657099Y1668850D03*
X674999Y1676550D03*
X656499Y1697050D03*
X675499Y1738050D03*
X665399Y1752350D03*
X675499Y1757050D03*
X675999Y1769050D03*
X659159Y1792278D03*
X659549Y1815384D03*
X667999Y1870950D03*
X669399Y1855350D03*
X674899Y1892350D03*
X661299Y1890050D03*
X674899Y1911350D03*
X661299Y1909050D03*
X674899Y1920350D03*
X661299Y1918050D03*
X673899Y1938850D03*
X660299Y1936550D03*
Y1955550D03*
X673899Y1966850D03*
Y1957850D03*
X660299Y1964550D03*
X659299Y1976250D03*
X661999Y1986550D03*
X680499Y6550D03*
X694999Y62650D03*
Y81650D03*
X695999Y102650D03*
X688999Y196550D03*
X677999Y218050D03*
X683499Y263050D03*
Y248550D03*
X680500Y280700D03*
X682999Y300050D03*
Y319050D03*
X683999Y340050D03*
X694999Y480550D03*
X695999Y501550D03*
X695499Y521050D03*
X691399Y548350D03*
X692399Y569350D03*
X691899Y588850D03*
X690499Y623050D03*
X693999Y648150D03*
X678499Y671050D03*
X679299Y703050D03*
X678499Y688550D03*
X681899Y713650D03*
X696299Y741850D03*
X694599Y763450D03*
X685999Y780050D03*
X687099Y804650D03*
Y823650D03*
X688099Y844650D03*
X687099Y896350D03*
Y915350D03*
X688099Y936350D03*
X678299Y978350D03*
Y997350D03*
X694999Y993050D03*
X692999Y1011550D03*
Y1026050D03*
Y1043550D03*
X692499Y1063050D03*
Y1082050D03*
X689999Y1105550D03*
X695999Y1203050D03*
Y1235050D03*
Y1217550D03*
X684299Y1249550D03*
X695999Y1323350D03*
X677999Y1347550D03*
X694999Y1360050D03*
X680299Y1365850D03*
X694999Y1379050D03*
X681299Y1393150D03*
X692999Y1406550D03*
X694999Y1388050D03*
X678299Y1425050D03*
X692999Y1421050D03*
X686999Y1468850D03*
X685299Y1551950D03*
X681299Y1579150D03*
X693599Y1602450D03*
X686699Y1638650D03*
X691999Y1660550D03*
X693099Y1722350D03*
X690499Y1744950D03*
X694599Y1768450D03*
X693549Y1793134D03*
X686473Y1818375D03*
X686999Y1870250D03*
X690899Y1855850D03*
X696299Y1898850D03*
X676399Y1901150D03*
X695299Y1926450D03*
X685499Y1940050D03*
X696299Y1976250D03*
X678799Y1975750D03*
X685499Y1959050D03*
Y1968050D03*
X679499Y1987050D03*
X697999Y7050D03*
X712499Y6050D03*
X699699Y141750D03*
Y160750D03*
X700699Y181750D03*
X711999Y218050D03*
X711499Y252550D03*
X711999Y307550D03*
Y293050D03*
Y325050D03*
X711499Y344550D03*
X712699Y434450D03*
X713699Y455450D03*
X713199Y474950D03*
Y489450D03*
X712599Y521050D03*
X713599Y542050D03*
X713099Y561550D03*
X699999Y610050D03*
X717099Y636050D03*
X702999Y656050D03*
Y688050D03*
Y670550D03*
X710899Y751150D03*
X716599Y736850D03*
X706999Y792550D03*
X707499Y773050D03*
X706999Y811550D03*
X707999Y832550D03*
X705999Y851050D03*
Y865550D03*
X707399Y899550D03*
Y918550D03*
X706499Y942550D03*
X713999Y1017050D03*
Y1031550D03*
X713499Y1068550D03*
X713999Y1049050D03*
X709999Y1105550D03*
X700499Y1118550D03*
X704299Y1132650D03*
X716999Y1148150D03*
X697499Y1153550D03*
X717999Y1169150D03*
X697499Y1172550D03*
X713399Y1178750D03*
X697999Y1184550D03*
X713599Y1214650D03*
X714399Y1199750D03*
X708699Y1243550D03*
X709699Y1264550D03*
X707899Y1346250D03*
X702299Y1404450D03*
X713899Y1386450D03*
X716899Y1459850D03*
X700899Y1450250D03*
X716199Y1503050D03*
X714599Y1533950D03*
X708899Y1549250D03*
X698599Y1568550D03*
X706700Y1579900D03*
X717099Y1702450D03*
X702599Y1730550D03*
X715999Y1744050D03*
X709099Y1751850D03*
X715999Y1763050D03*
Y1772050D03*
X706549Y1793634D03*
X717000Y1812384D03*
X705000Y1811900D03*
X711500Y1817700D03*
X704300Y1828400D03*
X697999Y1844550D03*
X706399Y1855850D03*
X705599Y1891850D03*
X716599Y1918450D03*
X698299Y1948050D03*
X711899Y1944050D03*
X709199Y1962950D03*
X717999Y1987550D03*
X702499D03*
X729999Y6550D03*
X725499Y23550D03*
X725999Y45050D03*
X725499Y62050D03*
X725999Y77550D03*
Y92050D03*
Y106550D03*
X738199Y137450D03*
X725999Y124050D03*
X725499Y143550D03*
Y162550D03*
X726499Y183550D03*
X728899Y204550D03*
X729499Y218550D03*
X723200Y275500D03*
X737999Y467050D03*
X738999Y488050D03*
X738499Y507550D03*
Y539550D03*
Y522050D03*
X737999Y559050D03*
X731499Y572050D03*
Y586550D03*
Y604050D03*
X721499Y617550D03*
X729699Y640350D03*
X723499Y654850D03*
X739399Y688150D03*
X720899Y712250D03*
X732499Y729250D03*
X727099Y715050D03*
X733799Y761450D03*
X723999Y783350D03*
Y802350D03*
X724999Y823350D03*
X728499Y841850D03*
X729999Y862850D03*
Y881850D03*
X730999Y902850D03*
X723699Y936250D03*
Y955250D03*
X724699Y976250D03*
X734999Y1030550D03*
Y1045050D03*
Y1062550D03*
X727499Y1106050D03*
X737999Y1119050D03*
X720499Y1118550D03*
X727499Y1132650D03*
X737999Y1159550D03*
Y1187550D03*
Y1178550D03*
X735999Y1206050D03*
X725499Y1231650D03*
X735999Y1220550D03*
X725499Y1250650D03*
X723499Y1278150D03*
X725499Y1259650D03*
X723499Y1292650D03*
X719199Y1322350D03*
X739199Y1348950D03*
X734199Y1373850D03*
X736199Y1399050D03*
X737799Y1428350D03*
X721899Y1419050D03*
X719499Y1446650D03*
X729199Y1492750D03*
X735799Y1533650D03*
X734499Y1563550D03*
X722199Y1564250D03*
X719999Y1605050D03*
X732999Y1620050D03*
X738799Y1677250D03*
X727399Y1694350D03*
X739199Y1716750D03*
X721199Y1723750D03*
X729999Y1756450D03*
X729499Y1778750D03*
X728099Y1844750D03*
X723199Y1867950D03*
X725899Y1855350D03*
X732999Y1868550D03*
X728299Y1888850D03*
X732199Y1878750D03*
X728799Y1908150D03*
Y1933050D03*
X736799Y1919450D03*
X730499Y1954650D03*
X721499Y1974550D03*
X737499Y1987050D03*
X749499Y6550D03*
X751499Y48350D03*
X757499Y44050D03*
Y63050D03*
X758499Y84050D03*
X752099Y112150D03*
X757999Y154550D03*
Y159050D03*
X753999Y154550D03*
Y159050D03*
X749499Y218550D03*
X755499Y314550D03*
X755346Y319149D03*
X751539Y313984D03*
X751499Y318050D03*
X749899Y398550D03*
X750899Y419550D03*
X750399Y453550D03*
Y439050D03*
X755199Y488150D03*
X756199Y509150D03*
X755699Y528650D03*
X754499Y564650D03*
X755499Y585650D03*
X754999Y605150D03*
X744999Y626550D03*
X751499Y679148D03*
X757400Y686300D03*
X747999Y670750D03*
X754999Y694050D03*
X749999Y700050D03*
X749499Y716050D03*
X744999Y715550D03*
X749999Y720050D03*
X745499D03*
X749799Y767450D03*
X743099Y785350D03*
X751999Y817050D03*
X751499Y855550D03*
Y836550D03*
X751599Y887350D03*
Y906350D03*
X752599Y927350D03*
X749999Y946550D03*
Y965550D03*
X751399Y1004550D03*
X750999Y986550D03*
X751399Y1023550D03*
X752399Y1052550D03*
X753999Y1100050D03*
X755499Y1119050D03*
X749999Y1119550D03*
X748999Y1115550D03*
X748499Y1111550D03*
X758799Y1171150D03*
Y1190150D03*
Y1199150D03*
X756799Y1232150D03*
Y1217650D03*
X757399Y1258650D03*
Y1239650D03*
X740499Y1252550D03*
X757399Y1267650D03*
X740499Y1270050D03*
X740799Y1298750D03*
X755399Y1300650D03*
Y1286150D03*
X742099Y1320650D03*
X754999Y1420050D03*
Y1437550D03*
X741099Y1450250D03*
Y1498150D03*
X747199Y1509150D03*
X755499Y1507550D03*
X751000Y1517000D03*
X757500Y1522500D03*
X751000Y1521000D03*
Y1525000D03*
X755499Y1568550D03*
X743400Y1578700D03*
X751300Y1604900D03*
X756299Y1679050D03*
X750099Y1694950D03*
X756499Y1712150D03*
X747499Y1734350D03*
X756900Y1766000D03*
X752900D03*
X751899Y1752150D03*
X747799Y1766750D03*
X751999Y1775550D03*
X756617Y1780067D03*
X752657Y1779496D03*
X755999Y1775550D03*
X753558Y1769946D03*
X757518Y1770517D03*
X744049Y1791634D03*
X740549Y1802634D03*
X753949Y1798194D03*
X740549Y1810384D03*
X747599Y1844250D03*
X744699Y1868450D03*
X758399Y1868350D03*
X743399Y1855850D03*
X743799Y1888850D03*
X753699Y1879250D03*
X755299Y1902150D03*
X739799D03*
X755500Y1914500D03*
X746499Y1974250D03*
X754999Y1987550D03*
X764999Y6550D03*
X763399Y24150D03*
X774399Y54050D03*
X775399Y80250D03*
X778399Y105250D03*
X767399Y140150D03*
X760799Y181950D03*
X779399Y200550D03*
X766999Y219050D03*
X781478Y363924D03*
X776978D03*
X772478Y359924D03*
Y363924D03*
X774999Y476550D03*
Y462050D03*
Y494050D03*
X774499Y513550D03*
Y532550D03*
X775499Y553550D03*
X777499Y638050D03*
X764599Y655750D03*
X777499Y664550D03*
X771800Y686600D03*
X766499Y699050D03*
Y705550D03*
X771196Y764382D03*
Y760382D03*
X775696Y764382D03*
X780196D03*
X778999Y806950D03*
X763099Y796350D03*
X775199Y839250D03*
Y858250D03*
X776199Y879250D03*
X772199Y920650D03*
Y939650D03*
X773199Y960650D03*
X776899Y988050D03*
Y1007050D03*
X777899Y1028050D03*
X760999Y1095550D03*
X773499Y1101050D03*
X769499D03*
X773499Y1105050D03*
X769499D03*
X780333Y1165892D03*
X775833D03*
X771333Y1161892D03*
Y1165892D03*
X762499Y1335550D03*
X779399Y1361850D03*
X762499Y1353050D03*
X773999Y1393450D03*
X763399Y1401450D03*
X769300Y1488100D03*
X779000Y1488400D03*
X771399Y1474550D03*
X770999Y1500050D03*
X780499D03*
X773499Y1509050D03*
X769499D03*
X778327Y1569796D03*
X773327Y1565796D03*
X773827Y1569796D03*
X768500Y1577500D03*
X776999Y1647650D03*
X765099Y1664950D03*
X770399Y1699650D03*
X779999Y1717050D03*
X770099Y1730350D03*
X779899Y1748150D03*
X765600Y1756800D03*
X767159Y1792364D03*
X765099Y1844750D03*
X779699Y1867950D03*
X779399Y1855850D03*
X763899D03*
X780799Y1888850D03*
X763299Y1888350D03*
X769199Y1879250D03*
X774499Y1908050D03*
X765999D03*
X773999Y1923550D03*
X767999Y1923050D03*
X774499Y1930050D03*
X768999D03*
X775999Y1916050D03*
X768499Y1917550D03*
X775814Y1975699D03*
X770814Y1971713D03*
X771814Y1975713D03*
X777499Y1987550D03*
X784499Y6050D03*
X801999Y6550D03*
X796999Y27050D03*
X797499Y48550D03*
X796999Y65550D03*
X797499Y81050D03*
Y95550D03*
Y110050D03*
X796599Y123450D03*
X797499Y127550D03*
X796999Y147050D03*
Y166050D03*
X797999Y187050D03*
X786499Y219050D03*
X800999Y216550D03*
X796873Y307571D03*
Y303071D03*
Y298571D03*
Y294071D03*
X784478Y355424D03*
Y359924D03*
X789999Y570050D03*
Y602050D03*
Y584550D03*
X785499Y641050D03*
X794999Y664550D03*
X786500Y686100D03*
X798000Y686400D03*
X782999Y699550D03*
X794331Y698353D03*
Y702853D03*
Y707353D03*
Y711853D03*
X799385Y761436D03*
X783196Y760382D03*
Y755882D03*
X802499Y814550D03*
X801999Y834050D03*
Y853050D03*
X800999Y892550D03*
Y907050D03*
Y924550D03*
X800499Y944050D03*
Y963050D03*
X801499Y984050D03*
X800999Y1005550D03*
Y1020050D03*
Y1037550D03*
X783999Y1096550D03*
X789499Y1099550D03*
X802499Y1097566D03*
X798499D03*
X783333Y1157392D03*
Y1161892D03*
X790999Y1194550D03*
Y1175550D03*
X791499Y1206550D03*
X789499Y1225050D03*
Y1257050D03*
Y1239550D03*
X788999Y1278150D03*
X791999Y1294450D03*
X795299Y1326650D03*
X799999Y1340550D03*
X798299Y1344250D03*
X799999Y1358050D03*
X781999Y1434650D03*
X786500Y1488600D03*
X801300Y1489000D03*
X786999Y1506550D03*
X795999Y1509550D03*
Y1504550D03*
Y1518550D03*
Y1514050D03*
X785827Y1561296D03*
Y1565796D03*
X782827Y1569796D03*
X797299Y1646650D03*
X802899Y1670550D03*
X782999Y1668050D03*
Y1687050D03*
X783499Y1699050D03*
X794499Y1734550D03*
X787900Y1758800D03*
X801099Y1844750D03*
X785599D03*
X791799Y1855850D03*
X797199Y1868450D03*
X788699Y1878750D03*
X783499Y1907050D03*
X790499Y1913050D03*
X795526Y1909696D03*
X795493Y1913696D03*
X795501Y1917696D03*
X795499Y1922050D03*
X783814Y1967213D03*
Y1971713D03*
X784016Y1975708D03*
X789299Y1983850D03*
X792999Y1987550D03*
X818999Y6050D03*
X817599Y43750D03*
X813299Y49350D03*
Y68350D03*
X814299Y89350D03*
X813299Y110850D03*
X821199Y137450D03*
X805899Y126150D03*
X809373Y307571D03*
Y297571D03*
Y292571D03*
X808999Y303050D03*
X821499Y314050D03*
X819299Y413250D03*
Y394250D03*
X820299Y434250D03*
X802999Y466050D03*
X803999Y487050D03*
X803499Y506550D03*
Y538550D03*
Y521050D03*
X802999Y558050D03*
X814499Y569550D03*
Y601550D03*
Y584050D03*
X809700Y686300D03*
X806300Y670600D03*
X806831Y701853D03*
Y706853D03*
X806999Y697050D03*
X806831Y711853D03*
X811499Y767550D03*
Y782050D03*
Y799550D03*
X802999Y874050D03*
X811499Y1097050D03*
X807499D03*
X807341Y1111216D03*
Y1101216D03*
X806999Y1106050D03*
X807341Y1116216D03*
X808299Y1175850D03*
X806599Y1189750D03*
X803599Y1211050D03*
X810199Y1229350D03*
Y1248350D03*
Y1257350D03*
X808199Y1275850D03*
Y1290350D03*
X822199Y1335250D03*
X819199Y1353550D03*
X806499Y1390550D03*
X803299Y1426650D03*
X806499Y1408050D03*
X805899Y1464250D03*
X809245Y1508722D03*
Y1503722D03*
Y1518722D03*
X808999Y1513550D03*
X813300Y1604100D03*
X803599Y1618350D03*
X814599Y1642650D03*
X823499Y1674050D03*
X808899Y1698450D03*
X823499Y1693050D03*
Y1702050D03*
X824100Y1719900D03*
X819400Y1721900D03*
X819200Y1727100D03*
X808299Y1755250D03*
X809299Y1856350D03*
X818900Y1870800D03*
X806199Y1879250D03*
X807936Y1914865D03*
Y1910365D03*
X807997Y1922865D03*
X808005Y1918865D03*
X813599Y1979950D03*
X812499Y1987050D03*
X836499Y6550D03*
X824899Y25150D03*
X844799Y19850D03*
X839999Y46050D03*
X840499Y55050D03*
X840999Y62550D03*
X841499Y71550D03*
X843499Y82550D03*
X838999Y85050D03*
X837999Y91050D03*
X838499Y107050D03*
Y99550D03*
X839499Y119050D03*
X837499Y138550D03*
X838499Y145050D03*
X838999Y313550D03*
X838499Y352050D03*
X839299Y390950D03*
Y409950D03*
X840299Y430950D03*
X824899Y500450D03*
X825899Y521450D03*
X825399Y540950D03*
X834599Y543050D03*
X835599Y564050D03*
X835099Y583550D03*
X841000Y671100D03*
X836149Y714050D03*
X835999Y767050D03*
X837799Y754150D03*
X835999Y781550D03*
Y799050D03*
X825199Y850850D03*
X827699Y873450D03*
Y892450D03*
X828699Y913450D03*
X826999Y963150D03*
Y982150D03*
X827999Y1003150D03*
X841999Y1118550D03*
X836149D03*
X839999Y1157550D03*
X831499Y1181550D03*
Y1209550D03*
Y1200550D03*
X829499Y1228050D03*
Y1242550D03*
X828199Y1267850D03*
X826199Y1294450D03*
X831499Y1324950D03*
X841999Y1341050D03*
Y1358550D03*
X825500Y1379000D03*
X834499Y1397550D03*
X836600Y1416500D03*
X843999Y1523550D03*
X839499D03*
X839899Y1562050D03*
X825999Y1578050D03*
X826499Y1609050D03*
X827199Y1622750D03*
X841499Y1638950D03*
X837199Y1660550D03*
X839199Y1683550D03*
X842799Y1701150D03*
X829200Y1719800D03*
X844499Y1788050D03*
X842500Y1799000D03*
X827999Y1791550D03*
X829799Y1856350D03*
X833199Y1868450D03*
X842199Y1879250D03*
X833100Y1878500D03*
X843999Y1928550D03*
X838999D03*
X840999Y1970550D03*
X829499Y1980250D03*
X829999Y1987550D03*
X855999Y6550D03*
X860799Y24150D03*
X865499Y39550D03*
X854499D03*
X856499Y71050D03*
X855499Y82050D03*
X845999Y111050D03*
X853999Y132550D03*
X865499Y125550D03*
X849999Y145550D03*
X863999Y313550D03*
X858400Y352300D03*
X847999Y352550D03*
X854499Y387550D03*
Y373050D03*
Y405050D03*
X853999Y424550D03*
Y443550D03*
X854999Y464550D03*
X860199Y525050D03*
X861199Y546050D03*
X860699Y565550D03*
X861800Y591200D03*
X860499Y607550D03*
X860796Y678632D03*
X859999Y713050D03*
Y767550D03*
X856299Y753150D03*
X846799Y754150D03*
X865000Y752100D03*
X859999Y782050D03*
Y799550D03*
X847799Y828250D03*
X857099Y873450D03*
X866199Y920350D03*
Y901350D03*
X850999Y962550D03*
Y943550D03*
X851999Y983550D03*
X859999Y1118550D03*
X846499Y1170450D03*
X856400Y1157700D03*
X848999Y1158050D03*
X863300Y1153800D03*
X845799Y1190450D03*
X849799Y1199750D03*
X851999Y1237550D03*
Y1218550D03*
X852499Y1249550D03*
X850499Y1268050D03*
X860099Y1295450D03*
X850499Y1300050D03*
Y1282550D03*
X861999Y1522550D03*
X850099Y1572250D03*
X858400Y1561900D03*
X850499Y1562050D03*
X865300Y1557700D03*
X864000Y1578200D03*
X849900Y1605100D03*
X852499Y1621350D03*
X855799Y1658250D03*
X855350Y1703201D03*
X864099Y1683550D03*
X853799Y1790850D03*
X863099Y1813150D03*
X862499Y1823550D03*
X854977Y1818994D03*
X861414Y1928550D03*
X864414Y1940050D03*
X850499Y1977950D03*
X856999Y1970050D03*
X849999Y1970550D03*
X865200Y1968000D03*
X864999Y1987050D03*
X849499D03*
X871499Y6550D03*
X885999Y21150D03*
X883999Y39050D03*
X881499Y70550D03*
X866999D03*
X876999Y82050D03*
X867499D03*
X886499Y99550D03*
Y104550D03*
X872499Y133050D03*
X875499Y125550D03*
X871499Y146050D03*
X871786Y218924D03*
Y203924D03*
X887400Y233555D03*
X871786Y233924D03*
X887400Y259700D03*
X879878Y247724D03*
X870600Y346700D03*
X875799Y386250D03*
Y405250D03*
X876799Y426250D03*
X884399Y443450D03*
Y462450D03*
X885399Y483450D03*
X870719Y609705D03*
X870773Y624705D03*
X870719Y639705D03*
X887401Y665000D03*
X881125Y652050D03*
X871786Y679436D03*
Y709482D03*
X871499Y689436D03*
X866499Y724550D03*
X871385Y719436D03*
X884499Y767050D03*
Y781550D03*
Y799050D03*
X873999Y830550D03*
Y845050D03*
Y862550D03*
X886999Y907350D03*
X867199Y941350D03*
X886999Y947250D03*
X870777Y1014948D03*
X870468Y1030227D03*
X886919Y1044478D03*
X870298Y1045227D03*
X880033Y1058592D03*
X887400Y1070600D03*
X871399Y1182850D03*
Y1201850D03*
Y1210850D03*
X869399Y1229350D03*
Y1243850D03*
X872099Y1268150D03*
X871399Y1291450D03*
X875399Y1322650D03*
X873499Y1356050D03*
X868499Y1392550D03*
Y1410050D03*
X871836Y1420460D03*
X886913Y1449010D03*
X871836Y1435460D03*
X879727Y1463696D03*
X871836Y1450460D03*
X887499Y1476050D03*
X873099Y1572550D03*
X886900Y1604100D03*
X866499Y1603050D03*
Y1612050D03*
X868099Y1635650D03*
X887299Y1620050D03*
X877699Y1646650D03*
X882999Y1678250D03*
X879200Y1698700D03*
X879900Y1709300D03*
X883900Y1709500D03*
X875900D03*
X882700Y1738300D03*
X886900Y1737900D03*
X872950Y1744401D03*
X866699Y1770950D03*
X879399Y1798150D03*
X869634Y1826876D03*
X871836Y1840972D03*
X887499Y1855550D03*
X869999Y1855972D03*
X887401Y1881500D03*
X879399Y1974550D03*
X873399Y1963650D03*
X868699Y1983250D03*
X884499Y1986550D03*
X890999Y6050D03*
X908499Y6550D03*
X902999Y22050D03*
X902499Y35050D03*
X905499Y56550D03*
X904999Y61550D03*
X904499Y74050D03*
X904999Y67550D03*
X890459Y100116D03*
X890499Y104550D03*
X889999Y132550D03*
X891999Y146050D03*
X906999Y243150D03*
Y224150D03*
X907999Y264150D03*
X906399Y295250D03*
Y314250D03*
X907399Y335250D03*
X904999Y370550D03*
Y385050D03*
Y402550D03*
X904499Y422050D03*
Y441050D03*
X905499Y462050D03*
X903999Y574378D03*
X898999Y622050D03*
Y604550D03*
X894000Y642400D03*
X900999Y652550D03*
Y670050D03*
X895999Y702550D03*
Y720050D03*
X898499Y830050D03*
Y844550D03*
X889699Y876050D03*
X898499Y862050D03*
X897299Y1182450D03*
X887999Y1209350D03*
X892499Y1224550D03*
Y1252550D03*
Y1243550D03*
X890499Y1271050D03*
Y1285550D03*
X890999Y1336550D03*
Y1354050D03*
X894499Y1423550D03*
Y1441050D03*
X895499Y1488050D03*
X902759Y1509585D03*
X894499Y1522050D03*
Y1539550D03*
X907500Y1604000D03*
X895999Y1661250D03*
X903599Y1686850D03*
X893200Y1721300D03*
X902900Y1709800D03*
X893200Y1730000D03*
X904814Y1789113D03*
X903299Y1814750D03*
X894999Y1829050D03*
X905299Y1852650D03*
X894000Y1868452D03*
X900299Y1876950D03*
X897299Y1904150D03*
X907599Y1930050D03*
X897599Y1938750D03*
X904299Y1954950D03*
X901999Y1987050D03*
X923999Y6050D03*
X917499Y21550D03*
X909499D03*
X909999Y35550D03*
X916499Y36050D03*
X928499Y51550D03*
X920900Y54700D03*
X928999Y56050D03*
X928499Y60550D03*
X928999Y65550D03*
X913699Y484650D03*
Y503650D03*
X914699Y524650D03*
X918999Y641550D03*
Y656050D03*
Y673550D03*
X918499Y693050D03*
Y712050D03*
X921899Y744850D03*
X919499Y733050D03*
X921899Y759350D03*
Y776850D03*
X921399Y796350D03*
X922399Y836350D03*
X921399Y815350D03*
X920399Y854850D03*
Y869350D03*
Y886850D03*
X919899Y906350D03*
Y925350D03*
X920899Y946350D03*
X921499Y999050D03*
Y1013550D03*
Y1031050D03*
X920999Y1050550D03*
Y1069550D03*
X925499Y1103550D03*
X921999Y1090550D03*
X925499Y1118050D03*
Y1135550D03*
X924999Y1174050D03*
Y1155050D03*
X925999Y1195050D03*
Y1207050D03*
Y1221550D03*
Y1239050D03*
X925499Y1258550D03*
Y1277550D03*
X926499Y1298550D03*
X928499Y1325350D03*
X925999Y1365050D03*
Y1379550D03*
Y1397050D03*
X925499Y1416550D03*
Y1435550D03*
X926499Y1456550D03*
X924999Y1485550D03*
Y1471050D03*
Y1503050D03*
X914599Y1521650D03*
X924499Y1522550D03*
X910899Y1549250D03*
X924499Y1541550D03*
X909700Y1576400D03*
X925499Y1562550D03*
X925599Y1612050D03*
X923599Y1634350D03*
X908899Y1630050D03*
X914899Y1657550D03*
X922599Y1682150D03*
X911299Y1800850D03*
X928000Y1818500D03*
X922899Y1853650D03*
X914999Y1868050D03*
Y1887050D03*
X914899Y1912450D03*
X915499Y1899050D03*
X916599Y1942650D03*
X914899Y1972250D03*
X921499Y1986550D03*
X941499Y6550D03*
X929999Y32550D03*
X940499Y33050D03*
X945499Y33550D03*
X943499Y48050D03*
Y55050D03*
Y72550D03*
X942999Y61550D03*
Y66550D03*
X943499Y78050D03*
X939199Y142050D03*
X932499Y191550D03*
Y206050D03*
Y223550D03*
X931999Y243050D03*
Y262050D03*
X932999Y283050D03*
X933499Y304050D03*
Y318550D03*
Y336050D03*
X932999Y355550D03*
Y374550D03*
X933999Y395550D03*
X933499Y429550D03*
Y415050D03*
Y447050D03*
X932999Y466550D03*
Y485550D03*
X933999Y506550D03*
X935499Y539050D03*
Y524550D03*
Y556550D03*
X934999Y576050D03*
X950299Y599650D03*
X934999Y595050D03*
X950299Y614150D03*
X935999Y616050D03*
X950299Y631650D03*
X949799Y651150D03*
Y670150D03*
X950799Y691150D03*
X944499Y750050D03*
Y735550D03*
Y767550D03*
X943999Y787050D03*
Y806050D03*
X944999Y827050D03*
X942999Y845550D03*
Y877550D03*
Y860050D03*
X942499Y897050D03*
Y916050D03*
X943499Y937050D03*
X949299Y977450D03*
Y991950D03*
Y1009450D03*
X948799Y1047950D03*
Y1028950D03*
X949799Y1068950D03*
Y1080950D03*
X950699Y1107750D03*
Y1122250D03*
Y1139750D03*
X950199Y1159250D03*
Y1178250D03*
X950699Y1262750D03*
Y1281750D03*
X943799Y1342950D03*
Y1380850D03*
X944000Y1391900D03*
X946700Y1426500D03*
X944000Y1511300D03*
X943199Y1531650D03*
X933199Y1577550D03*
X944499Y1632650D03*
X950100Y1626100D03*
X940499Y1656950D03*
X941499Y1679550D03*
X931499Y1702050D03*
X949799Y1756250D03*
X941800Y1787700D03*
X941499Y1776250D03*
X934200Y1793500D03*
X932199Y1801850D03*
X937199Y1869950D03*
X937499Y1893850D03*
X938199Y1917150D03*
X947499Y1936050D03*
X930999Y1931050D03*
X945199Y1946350D03*
X930999Y1950050D03*
X946199Y1966650D03*
X931499Y1962050D03*
X930199Y1979550D03*
X936999Y1986550D03*
X960999Y6550D03*
X954799Y17850D03*
X965999Y47050D03*
Y56050D03*
Y64050D03*
X966499Y73050D03*
Y82050D03*
X968399Y137150D03*
X967399Y180350D03*
X958799Y167350D03*
X956099Y181350D03*
X952799Y199150D03*
Y213650D03*
Y231150D03*
X952299Y250650D03*
Y269650D03*
X953299Y290650D03*
X952799Y324650D03*
Y310150D03*
Y342150D03*
X952299Y361650D03*
Y380650D03*
X953299Y401650D03*
X954799Y434150D03*
Y419650D03*
Y451650D03*
X966199Y473350D03*
Y492350D03*
X951799Y489650D03*
X967199Y513350D03*
X951799Y504150D03*
Y521650D03*
X951299Y560150D03*
Y541150D03*
X966799Y566350D03*
X952299Y581150D03*
X966799Y585350D03*
X967799Y606350D03*
X969499Y639050D03*
Y653550D03*
Y671050D03*
X968999Y709550D03*
Y690550D03*
X969999Y730550D03*
Y744250D03*
Y758750D03*
Y776250D03*
X969499Y795750D03*
Y814750D03*
X970499Y835750D03*
Y847750D03*
Y862250D03*
X969999Y899250D03*
X970499Y879750D03*
X969999Y918250D03*
X970999Y939250D03*
X971999Y996550D03*
Y1011050D03*
Y1028550D03*
X971499Y1067050D03*
Y1048050D03*
X951199Y1211250D03*
Y1199250D03*
Y1225750D03*
Y1243250D03*
X951699Y1302750D03*
X965099Y1324350D03*
X952499Y1361850D03*
X964400Y1409700D03*
X972000Y1442000D03*
Y1437500D03*
X971700Y1448300D03*
X962500Y1436500D03*
Y1441000D03*
X952800Y1437500D03*
Y1442000D03*
X962200Y1447300D03*
X952500Y1448300D03*
X971500Y1467500D03*
X971700Y1457800D03*
Y1462300D03*
Y1452800D03*
X962000Y1466500D03*
X952300Y1467500D03*
X962200Y1451800D03*
X952500Y1452800D03*
X962200Y1456800D03*
Y1461300D03*
X952500Y1457800D03*
Y1462300D03*
X966000Y1475000D03*
X958800Y1472500D03*
X966000Y1479500D03*
Y1484000D03*
X958800Y1477000D03*
Y1481500D03*
X965700Y1489300D03*
X958500Y1486800D03*
X960200Y1495300D03*
X951500D03*
X960049Y1500300D03*
X951349D03*
X960049Y1504800D03*
X951349D03*
X966600Y1529100D03*
X961400Y1528700D03*
X961900Y1522400D03*
X967100Y1522800D03*
X962100Y1516000D03*
X967300Y1516400D03*
X961600Y1534400D03*
X972000Y1547500D03*
X966100D03*
X960900Y1547100D03*
X961400Y1540800D03*
X966600Y1541200D03*
X966800Y1534800D03*
X961600Y1552900D03*
X966800Y1553300D03*
X972000Y1566000D03*
X966100D03*
X960900Y1565600D03*
X961400Y1559300D03*
X966600Y1559700D03*
X961900Y1572400D03*
X967100Y1572800D03*
X966400Y1585500D03*
X961200Y1585100D03*
X961700Y1578800D03*
X966900Y1579200D03*
X966500Y1592000D03*
X961300Y1591600D03*
X966300Y1598400D03*
X961100Y1598000D03*
X960600Y1604300D03*
X971700Y1604700D03*
X965800D03*
X957799Y1646950D03*
X955499Y1690850D03*
X958799Y1715750D03*
X965349Y1742000D03*
X954499Y1783550D03*
X971000Y1803000D03*
X971500Y1871500D03*
X966799Y1892150D03*
X955499Y1893050D03*
Y1902050D03*
X954099Y1915450D03*
X955799Y1951950D03*
X971499Y1956050D03*
Y1937050D03*
X953799Y1977950D03*
X971499Y1965050D03*
X956499Y1986050D03*
X976499Y6550D03*
X974699Y21450D03*
X991399Y22450D03*
X977399Y44050D03*
X974699Y64650D03*
X991999Y56050D03*
X983099Y83650D03*
X977699Y109150D03*
X981099Y123450D03*
X988699Y174350D03*
X982999Y189050D03*
Y203550D03*
Y221050D03*
X982499Y240550D03*
Y259550D03*
X983499Y280550D03*
X983999Y301550D03*
Y316050D03*
Y333550D03*
X983499Y353050D03*
Y372050D03*
X983999Y412550D03*
X984499Y393050D03*
X983999Y427050D03*
Y444550D03*
X983499Y464050D03*
Y483050D03*
X984499Y504050D03*
X985999Y536550D03*
Y522050D03*
Y554050D03*
X985499Y573550D03*
Y592550D03*
X986499Y613550D03*
X992999Y894550D03*
Y913550D03*
X972499Y1088050D03*
X975999Y1101050D03*
Y1115550D03*
X975499Y1152550D03*
X975999Y1133050D03*
X975499Y1171550D03*
X976499Y1192550D03*
Y1204550D03*
Y1219050D03*
Y1236550D03*
X975999Y1256050D03*
Y1275050D03*
X976999Y1296050D03*
X975100Y1342600D03*
X976499Y1362550D03*
Y1377050D03*
X992500Y1397300D03*
X973500Y1483000D03*
Y1478500D03*
X973200Y1488300D03*
X973500Y1474000D03*
X972549Y1502300D03*
Y1506800D03*
X972700Y1497300D03*
X973200Y1516400D03*
X972500Y1529100D03*
X973000Y1522800D03*
X972700Y1534800D03*
X972500Y1541200D03*
X972700Y1553300D03*
X972500Y1559700D03*
X973000Y1572800D03*
X972300Y1585500D03*
X972800Y1579200D03*
X972400Y1592000D03*
X972200Y1598400D03*
X989999Y1718050D03*
X993299Y1734350D03*
X976600Y1757100D03*
X976399Y1772250D03*
Y1791150D03*
X974699Y1914450D03*
X991999Y1915750D03*
X992299Y1929050D03*
X980999Y1933350D03*
X987999Y1949050D03*
Y1971950D03*
X989999Y1962650D03*
X973999Y1986550D03*
X995999Y6050D03*
X1013499Y6550D03*
X1002699Y40050D03*
X1005299Y71350D03*
X994399Y101250D03*
X1010599Y115550D03*
X1005299Y179950D03*
Y194450D03*
Y211950D03*
X1004799Y231450D03*
Y250450D03*
X1005799Y271450D03*
X1005299Y305450D03*
Y290950D03*
Y322950D03*
X1004799Y342450D03*
Y361450D03*
X1005799Y382450D03*
X1007299Y400450D03*
Y432450D03*
Y414950D03*
X1000699Y463350D03*
Y482350D03*
X1001699Y503350D03*
X1003999Y526850D03*
X1003499Y546350D03*
Y565350D03*
X1004499Y586350D03*
X1005999Y618850D03*
Y604350D03*
Y636350D03*
X994999Y747550D03*
Y733050D03*
Y765050D03*
X994499Y784550D03*
Y803550D03*
X995499Y824550D03*
X993499Y857550D03*
Y843050D03*
Y875050D03*
X994499Y941550D03*
X993999Y934550D03*
X994499Y956050D03*
Y973550D03*
X993999Y993050D03*
Y1012050D03*
X994999Y1033050D03*
Y1045050D03*
X998599Y1110950D03*
Y1096450D03*
Y1128450D03*
X998099Y1147950D03*
Y1166950D03*
X999099Y1187950D03*
Y1214450D03*
Y1199950D03*
Y1231950D03*
X998599Y1251450D03*
Y1270450D03*
X999599Y1291450D03*
X996500Y1324800D03*
X1000700Y1358100D03*
X994200Y1421500D03*
X1008999Y1702450D03*
X1008599Y1716050D03*
X994999Y1748950D03*
X999999Y1775250D03*
X1009999Y1797450D03*
X993499Y1805550D03*
X1007599Y1818450D03*
X993499Y1824550D03*
X1003599Y1846650D03*
X993499Y1833550D03*
X1011299Y1860650D03*
X995699Y1858950D03*
X1001599Y1921450D03*
X1000999Y1946350D03*
X1002500Y1953500D03*
X1005000Y1980500D03*
X994999Y1986550D03*
X1022000Y15500D03*
X1020499Y50550D03*
X1020999Y33050D03*
Y70050D03*
Y85550D03*
Y105050D03*
X1020499Y122550D03*
X1020999Y158550D03*
X1021499Y141050D03*
Y178050D03*
Y193550D03*
Y213050D03*
X1020999Y230550D03*
Y252050D03*
X1020499Y269550D03*
X1020999Y304550D03*
Y289050D03*
Y324050D03*
X1020499Y341550D03*
Y391550D03*
X1020999Y374050D03*
Y411050D03*
Y426550D03*
Y446050D03*
X1020499Y463550D03*
X1021999Y486550D03*
X1021499Y504050D03*
X1021999Y539050D03*
Y523550D03*
Y558550D03*
X1021499Y576050D03*
X1020499Y623050D03*
X1020999Y605550D03*
Y642550D03*
Y658050D03*
Y677550D03*
X1020499Y695050D03*
X1020999Y720050D03*
X1020499Y737550D03*
X1020999Y772550D03*
Y757050D03*
Y792050D03*
X1020499Y809550D03*
Y828050D03*
X1019999Y845550D03*
X1020499Y865050D03*
Y880550D03*
X1019999Y917550D03*
X1020499Y900050D03*
X1019999Y934050D03*
X1019499Y951550D03*
X1019999Y971050D03*
Y986550D03*
X1019499Y1023550D03*
X1019999Y1006050D03*
Y1043050D03*
Y1058550D03*
X1020499Y1081550D03*
X1019999Y1099050D03*
X1020499Y1118550D03*
Y1134050D03*
X1019499Y1146050D03*
X1018999Y1163550D03*
X1019499Y1183050D03*
Y1198550D03*
X1016999Y1219050D03*
X1016499Y1236550D03*
X1016999Y1256050D03*
Y1271550D03*
X1016499Y1301050D03*
X1022599Y1322950D03*
X1023300Y1344400D03*
X1024300Y1365200D03*
Y1393600D03*
X1022299Y1715750D03*
X1016899Y1731650D03*
X1020299Y1746650D03*
X1015299Y1765950D03*
X1026899Y1768550D03*
X1022999Y1784550D03*
X1022499Y1802050D03*
X1022999Y1821550D03*
Y1837050D03*
X1020999Y1860050D03*
X1020499Y1877550D03*
X1020999Y1912550D03*
Y1897050D03*
X1017499Y1954550D03*
X1017999Y1937050D03*
X1023000Y1973000D03*
X1017999Y1987050D03*
G54D21*
G01X-53190Y-209897D02*
Y-192397D01*
G01X-44894D02*
X-53190Y-203189D01*
G01X-43584Y-209897D02*
X-49479Y-198231D01*
G01X-35909Y-209897D02*
Y-192397D01*
X-25865Y-209897D01*
Y-192397D01*
G01X-13387Y-209897D02*
X-15134Y-209605D01*
X-16662Y-208439D01*
X-17972Y-206689D01*
X-18846Y-204647D01*
X-19282Y-202314D01*
Y-199980D01*
X-18846Y-197647D01*
X-17972Y-195605D01*
X-16662Y-193856D01*
X-15134Y-192689D01*
X-13387Y-192397D01*
X-11641Y-192689D01*
X-10112Y-193856D01*
X-8802Y-195605D01*
X-7928Y-197647D01*
X-7492Y-199980D01*
Y-202314D01*
X-7928Y-204647D01*
X-8802Y-206689D01*
X-10112Y-208439D01*
X-11641Y-209605D01*
X-13387Y-209897D01*
G01X-472D02*
X8698Y-192397D01*
G01X-472D02*
X8698Y-209897D01*
G01X34310D02*
Y-192397D01*
X38676D01*
X40423Y-193272D01*
X41733Y-194439D01*
X42825Y-196188D01*
X43698Y-198231D01*
X43916Y-201147D01*
X43698Y-204064D01*
X42825Y-206106D01*
X41733Y-207856D01*
X40423Y-209022D01*
X38676Y-209897D01*
X34310D01*
G01X52246D02*
Y-192397D01*
X57705D01*
X59451Y-193272D01*
X60543Y-194439D01*
X60980Y-196772D01*
X60543Y-199106D01*
X59233Y-200564D01*
X57705Y-201439D01*
X52246D01*
G01X57705D02*
X60980Y-209897D01*
G01X71493Y-192397D02*
X76733D01*
G01X74113D02*
Y-209897D01*
G01X71493D02*
X76733D01*
G01X86154Y-192397D02*
X91613Y-209897D01*
X97072Y-192397D01*
G01X113480Y-209897D02*
X104746D01*
Y-192397D01*
X113480D01*
G01X109986Y-200855D02*
X104746D01*
G01X139746Y-209897D02*
Y-192397D01*
X144986D01*
X146733Y-193272D01*
X148043Y-195314D01*
X148480Y-197647D01*
X148043Y-199980D01*
X146951Y-201730D01*
X144986Y-202606D01*
X139746D01*
G01X157246Y-192397D02*
Y-209897D01*
X165980D01*
G01X173654D02*
X179113Y-192397D01*
X184572Y-209897D01*
G01X182606Y-203772D02*
X175619D01*
G01X191591Y-209897D02*
Y-192397D01*
X201635Y-209897D01*
Y-192397D01*
G01X218480Y-209897D02*
X209746D01*
Y-192397D01*
X218480D01*
G01X214986Y-200855D02*
X209746D01*
G01X250859Y-200564D02*
X251733Y-199689D01*
X252388Y-198231D01*
X252825Y-196188D01*
X252388Y-194439D01*
X251515Y-193272D01*
X249986Y-192397D01*
X244091D01*
Y-209897D01*
X251296D01*
X252825Y-208731D01*
X253698Y-206980D01*
X254135Y-204939D01*
X253698Y-202897D01*
X252388Y-201147D01*
X250859Y-200564D01*
X244091D01*
G01X266613Y-209897D02*
X264866Y-209605D01*
X263338Y-208439D01*
X262028Y-206689D01*
X261154Y-204647D01*
X260718Y-202314D01*
Y-199980D01*
X261154Y-197647D01*
X262028Y-195605D01*
X263338Y-193856D01*
X264866Y-192689D01*
X266613Y-192397D01*
X268359Y-192689D01*
X269888Y-193856D01*
X271198Y-195605D01*
X272072Y-197647D01*
X272508Y-199980D01*
Y-202314D01*
X272072Y-204647D01*
X271198Y-206689D01*
X269888Y-208439D01*
X268359Y-209605D01*
X266613Y-209897D01*
G01X278654D02*
X284113Y-192397D01*
X289572Y-209897D01*
G01X287606Y-203772D02*
X280619D01*
G01X297246Y-209897D02*
Y-192397D01*
X302705D01*
X304451Y-193272D01*
X305543Y-194439D01*
X305980Y-196772D01*
X305543Y-199106D01*
X304233Y-200564D01*
X302705Y-201439D01*
X297246D01*
G01X302705D02*
X305980Y-209897D01*
G01X314310D02*
Y-192397D01*
X318676D01*
X320423Y-193272D01*
X321733Y-194439D01*
X322825Y-196188D01*
X323698Y-198231D01*
X323916Y-201147D01*
X323698Y-204064D01*
X322825Y-206106D01*
X321733Y-207856D01*
X320423Y-209022D01*
X318676Y-209897D01*
X314310D01*
G01X94686Y-164897D02*
Y-147397D01*
X100363Y-161980D01*
X106040Y-147397D01*
Y-164897D01*
G01X117863D02*
X116553Y-164605D01*
X115243Y-163439D01*
X114369Y-161397D01*
X113933Y-159064D01*
X114369Y-156730D01*
X115243Y-154689D01*
X116553Y-153522D01*
X117863Y-153231D01*
X119173Y-153522D01*
X120483Y-154689D01*
X121356Y-156730D01*
X121575Y-159064D01*
X121356Y-161397D01*
X120483Y-163439D01*
X119173Y-164605D01*
X117863Y-164897D01*
G01X139293Y-147397D02*
Y-164897D01*
G01Y-162273D02*
X138420Y-163731D01*
X137109Y-164605D01*
X135581Y-164897D01*
X133835Y-164314D01*
X132525Y-162856D01*
X131651Y-161106D01*
X131433Y-159064D01*
X131651Y-157022D01*
X132525Y-155272D01*
X133835Y-153814D01*
X135581Y-153231D01*
X137109Y-153522D01*
X138201Y-154106D01*
X139293Y-155272D01*
G01X149588Y-157022D02*
X156575D01*
X155920Y-154980D01*
X154828Y-153814D01*
X153300Y-153231D01*
X151771Y-153522D01*
X150461Y-154397D01*
X149588Y-156439D01*
X149151Y-158189D01*
Y-159939D01*
X149588Y-161689D01*
X150680Y-163439D01*
X151990Y-164605D01*
X153518Y-164897D01*
X155046Y-164314D01*
X156575Y-162564D01*
G01X170363Y-164897D02*
Y-147397D01*
G01X376163Y-209897D02*
Y-192397D01*
X373543Y-195897D01*
G01Y-209897D02*
X378783D01*
G01X389515Y-195314D02*
X390825Y-193564D01*
X392353Y-192689D01*
X394100Y-192397D01*
X396283Y-192980D01*
X397811Y-194439D01*
X398248Y-196188D01*
X398030Y-197939D01*
X397156Y-199397D01*
X392790Y-202314D01*
X390825Y-204355D01*
X389515Y-207273D01*
X389078Y-209897D01*
X398248D01*
G01X413783D02*
Y-192397D01*
X405704Y-204939D01*
X416622D01*
G01X423860Y-206397D02*
X425169Y-208439D01*
X426916Y-209605D01*
X428881Y-209897D01*
X430628Y-209605D01*
X432375Y-208147D01*
X433466Y-206397D01*
X433685Y-204647D01*
X433248Y-202606D01*
X431720Y-201147D01*
X430191Y-200564D01*
X428226D01*
G01X430191D02*
X431501Y-199689D01*
X432593Y-198231D01*
X433030Y-196481D01*
X432593Y-194730D01*
X431501Y-193272D01*
X429536Y-192397D01*
X427571Y-192689D01*
X425606Y-193856D01*
G01X442015Y-195314D02*
X443325Y-193564D01*
X444853Y-192689D01*
X446600Y-192397D01*
X448783Y-192980D01*
X450311Y-194439D01*
X450748Y-196188D01*
X450530Y-197939D01*
X449656Y-199397D01*
X445290Y-202314D01*
X443325Y-204355D01*
X442015Y-207273D01*
X441578Y-209897D01*
X450748D01*
G01X363046Y-164897D02*
Y-147397D01*
X368286D01*
X370033Y-148272D01*
X371343Y-150314D01*
X371780Y-152647D01*
X371343Y-154980D01*
X370251Y-156730D01*
X368286Y-157606D01*
X363046D01*
G01X389716Y-148856D02*
X388406Y-147980D01*
X386878Y-147397D01*
X385131D01*
X383166Y-148272D01*
X381638Y-149730D01*
X380546Y-151481D01*
X379673Y-154397D01*
X379454Y-157022D01*
X379891Y-159647D01*
X380546Y-161397D01*
X381856Y-163147D01*
X383385Y-164314D01*
X384913Y-164897D01*
X386441D01*
X387970Y-164314D01*
X389280Y-163439D01*
X390372Y-162273D01*
G01X404159Y-155564D02*
X405033Y-154689D01*
X405688Y-153231D01*
X406125Y-151188D01*
X405688Y-149439D01*
X404815Y-148272D01*
X403286Y-147397D01*
X397391D01*
Y-164897D01*
X404596D01*
X406125Y-163731D01*
X406998Y-161980D01*
X407435Y-159939D01*
X406998Y-157897D01*
X405688Y-156147D01*
X404159Y-155564D01*
X397391D01*
G01X413363Y-170730D02*
X426463D01*
G01X432391Y-164897D02*
Y-147397D01*
X442435Y-164897D01*
Y-147397D01*
G01X454913Y-164897D02*
X453166Y-164605D01*
X451638Y-163439D01*
X450328Y-161689D01*
X449454Y-159647D01*
X449018Y-157314D01*
Y-154980D01*
X449454Y-152647D01*
X450328Y-150605D01*
X451638Y-148856D01*
X453166Y-147689D01*
X454913Y-147397D01*
X456659Y-147689D01*
X458188Y-148856D01*
X459498Y-150605D01*
X460372Y-152647D01*
X460808Y-154980D01*
Y-157314D01*
X460372Y-159647D01*
X459498Y-161689D01*
X458188Y-163439D01*
X456659Y-164605D01*
X454913Y-164897D01*
G01X505754Y-147397D02*
X511213Y-164897D01*
X516672Y-147397D01*
G01X533080Y-164897D02*
X524346D01*
Y-147397D01*
X533080D01*
G01X529586Y-155855D02*
X524346D01*
G01X541846Y-164897D02*
Y-147397D01*
X547305D01*
X549051Y-148272D01*
X550143Y-149439D01*
X550580Y-151772D01*
X550143Y-154106D01*
X548833Y-155564D01*
X547305Y-156439D01*
X541846D01*
G01X547305D02*
X550580Y-164897D01*
G01X563713Y-165480D02*
X563276Y-165189D01*
Y-164605D01*
X563713Y-164314D01*
X564150Y-164605D01*
Y-165189D01*
X563713Y-165480D01*
G01X537463Y-209897D02*
Y-192397D01*
X534843Y-195897D01*
G01Y-209897D02*
X540083D01*
G01X630546Y-147397D02*
Y-164897D01*
X639280D01*
G01X656343D02*
Y-153231D01*
G01Y-155272D02*
X655470Y-154106D01*
X654159Y-153522D01*
X652631Y-153231D01*
X651103Y-153814D01*
X649793Y-154980D01*
X648919Y-156730D01*
X648483Y-159064D01*
X648919Y-161397D01*
X649793Y-163147D01*
X651103Y-164314D01*
X652631Y-164897D01*
X654159Y-164605D01*
X655470Y-163731D01*
X656343Y-162564D01*
G01X665328Y-170147D02*
X666638Y-170730D01*
X668385Y-170147D01*
X669476Y-168981D01*
X670350Y-167522D01*
X671659Y-162856D01*
X674498Y-153231D01*
G01X667511D02*
X671659Y-162856D01*
G01X684138Y-157022D02*
X691125D01*
X690470Y-154980D01*
X689378Y-153814D01*
X687850Y-153231D01*
X686321Y-153522D01*
X685011Y-154397D01*
X684138Y-156439D01*
X683701Y-158189D01*
Y-159939D01*
X684138Y-161689D01*
X685230Y-163439D01*
X686540Y-164605D01*
X688068Y-164897D01*
X689596Y-164314D01*
X691125Y-162564D01*
G01X701856Y-164897D02*
Y-153231D01*
G01Y-155564D02*
X702948Y-154397D01*
X704040Y-153522D01*
X705568Y-153231D01*
X706659Y-153522D01*
X707970Y-154397D01*
G01X719138Y-162856D02*
X720230Y-164022D01*
X721758Y-164897D01*
X723068D01*
X724378Y-164314D01*
X725251Y-163439D01*
X725688Y-162273D01*
X725470Y-160522D01*
X724596Y-159647D01*
X720666Y-157897D01*
X719793Y-155855D01*
X720230Y-154397D01*
X721103Y-153522D01*
X722413Y-153231D01*
X723723Y-153522D01*
X725033Y-154397D01*
G01X691780Y-192397D02*
Y-209897D01*
X683046D01*
G01X674061Y-202606D02*
X672533Y-200564D01*
X671223Y-199397D01*
X669476Y-198814D01*
X667948Y-199397D01*
X666856Y-200564D01*
X665983Y-202314D01*
X665765Y-204355D01*
X665983Y-206106D01*
X666856Y-207856D01*
X668167Y-209314D01*
X669695Y-209897D01*
X671441Y-209314D01*
X672970Y-207564D01*
X673843Y-204939D01*
X674061Y-202022D01*
X673625Y-198231D01*
X672970Y-196188D01*
X671878Y-194147D01*
X670350Y-192689D01*
X668821Y-192397D01*
X667293Y-192980D01*
X666201Y-194439D01*
G01X781410Y-164897D02*
Y-147397D01*
X785776D01*
X787523Y-148272D01*
X788833Y-149439D01*
X789925Y-151188D01*
X790798Y-153231D01*
X791016Y-156147D01*
X790798Y-159064D01*
X789925Y-161106D01*
X788833Y-162856D01*
X787523Y-164022D01*
X785776Y-164897D01*
X781410D01*
G01X800438Y-157022D02*
X807425D01*
X806770Y-154980D01*
X805678Y-153814D01*
X804150Y-153231D01*
X802621Y-153522D01*
X801311Y-154397D01*
X800438Y-156439D01*
X800001Y-158189D01*
Y-159939D01*
X800438Y-161689D01*
X801530Y-163439D01*
X802840Y-164605D01*
X804368Y-164897D01*
X805896Y-164314D01*
X807425Y-162564D01*
G01X817938Y-162856D02*
X819030Y-164022D01*
X820558Y-164897D01*
X821868D01*
X823178Y-164314D01*
X824051Y-163439D01*
X824488Y-162273D01*
X824270Y-160522D01*
X823396Y-159647D01*
X819466Y-157897D01*
X818593Y-155855D01*
X819030Y-154397D01*
X819903Y-153522D01*
X821213Y-153231D01*
X822523Y-153522D01*
X823833Y-154397D01*
G01X838713Y-153231D02*
Y-164897D01*
G01Y-148564D02*
X838276Y-148272D01*
Y-147689D01*
X838713Y-147397D01*
X839150Y-147689D01*
Y-148272D01*
X838713Y-148564D01*
G01X853156Y-169272D02*
X854685Y-170439D01*
X856431Y-170730D01*
X857959Y-170439D01*
X859270Y-168981D01*
X860143Y-166939D01*
Y-153231D01*
G01Y-155564D02*
X859270Y-154397D01*
X857959Y-153522D01*
X856431Y-153231D01*
X854685Y-153814D01*
X853593Y-154980D01*
X852719Y-157022D01*
X852283Y-159064D01*
X852501Y-160814D01*
X853375Y-162856D01*
X854685Y-164314D01*
X856431Y-164897D01*
X857741Y-164605D01*
X859270Y-163439D01*
X860143Y-162273D01*
G01X870001Y-164897D02*
Y-153231D01*
G01Y-156147D02*
X870875Y-154689D01*
X872185Y-153522D01*
X873931Y-153231D01*
X875459Y-153522D01*
X876770Y-154689D01*
X877425Y-156730D01*
Y-164897D01*
G01X887938Y-157022D02*
X894925D01*
X894270Y-154980D01*
X893178Y-153814D01*
X891650Y-153231D01*
X890121Y-153522D01*
X888811Y-154397D01*
X887938Y-156439D01*
X887501Y-158189D01*
Y-159939D01*
X887938Y-161689D01*
X889030Y-163439D01*
X890340Y-164605D01*
X891868Y-164897D01*
X893396Y-164314D01*
X894925Y-162564D01*
G01X905656Y-164897D02*
Y-153231D01*
G01Y-155564D02*
X906748Y-154397D01*
X907840Y-153522D01*
X909368Y-153231D01*
X910459Y-153522D01*
X911770Y-154397D01*
G01X825596Y-209897D02*
Y-192397D01*
X831055D01*
X832801Y-193272D01*
X833893Y-194439D01*
X834330Y-196772D01*
X833893Y-199106D01*
X832583Y-200564D01*
X831055Y-201439D01*
X825596D01*
G01X831055D02*
X834330Y-209897D01*
G01X847463D02*
X846153Y-209605D01*
X844843Y-208439D01*
X843969Y-206397D01*
X843533Y-204064D01*
X843969Y-201730D01*
X844843Y-199689D01*
X846153Y-198522D01*
X847463Y-198231D01*
X848773Y-198522D01*
X850083Y-199689D01*
X850956Y-201730D01*
X851175Y-204064D01*
X850956Y-206397D01*
X850083Y-208439D01*
X848773Y-209605D01*
X847463Y-209897D01*
G01X861033D02*
Y-192397D01*
G01Y-201147D02*
X862125Y-199397D01*
X863435Y-198522D01*
X864745Y-198231D01*
X866709Y-198814D01*
X868020Y-199980D01*
X868893Y-202022D01*
Y-204355D01*
X868456Y-206689D01*
X867583Y-208439D01*
X866055Y-209605D01*
X864745Y-209897D01*
X863435Y-209605D01*
X862125Y-208731D01*
X861033Y-207273D01*
G01X952413Y-209897D02*
Y-192397D01*
X949793Y-195897D01*
G01Y-209897D02*
X955033D01*
G01X969913Y-192397D02*
X968166Y-192980D01*
X966856Y-194439D01*
X965983Y-196188D01*
X965328Y-198522D01*
X965110Y-201147D01*
X965328Y-203772D01*
X965983Y-206106D01*
X966856Y-207856D01*
X968166Y-209314D01*
X969913Y-209897D01*
X971659Y-209314D01*
X972970Y-207856D01*
X973843Y-206106D01*
X974498Y-203772D01*
X974716Y-201147D01*
X974498Y-198522D01*
X973843Y-196188D01*
X972970Y-194439D01*
X971659Y-192980D01*
X969913Y-192397D01*
G01X983483Y-210480D02*
X991343Y-192397D01*
G01X1004913Y-209897D02*
Y-192397D01*
X1002293Y-195897D01*
G01Y-209897D02*
X1007533D01*
G01X1018265Y-202606D02*
X1019793Y-200564D01*
X1021103Y-199397D01*
X1022850Y-198814D01*
X1024378Y-199397D01*
X1025470Y-200564D01*
X1026343Y-202314D01*
X1026561Y-204355D01*
X1026343Y-206106D01*
X1025470Y-207856D01*
X1024159Y-209314D01*
X1022631Y-209897D01*
X1020885Y-209314D01*
X1019356Y-207564D01*
X1018483Y-204939D01*
X1018265Y-202022D01*
X1018701Y-198231D01*
X1019356Y-196188D01*
X1020448Y-194147D01*
X1021976Y-192689D01*
X1023505Y-192397D01*
X1025033Y-192980D01*
X1026125Y-194439D01*
G01X1035983Y-210480D02*
X1043843Y-192397D01*
G01X1053265Y-195314D02*
X1054575Y-193564D01*
X1056103Y-192689D01*
X1057850Y-192397D01*
X1060033Y-192980D01*
X1061561Y-194439D01*
X1061998Y-196188D01*
X1061780Y-197939D01*
X1060906Y-199397D01*
X1056540Y-202314D01*
X1054575Y-204355D01*
X1053265Y-207273D01*
X1052828Y-209897D01*
X1061998D01*
G01X1074913Y-192397D02*
X1073166Y-192980D01*
X1071856Y-194439D01*
X1070983Y-196188D01*
X1070328Y-198522D01*
X1070110Y-201147D01*
X1070328Y-203772D01*
X1070983Y-206106D01*
X1071856Y-207856D01*
X1073166Y-209314D01*
X1074913Y-209897D01*
X1076659Y-209314D01*
X1077970Y-207856D01*
X1078843Y-206106D01*
X1079498Y-203772D01*
X1079716Y-201147D01*
X1079498Y-198522D01*
X1078843Y-196188D01*
X1077970Y-194439D01*
X1076659Y-192980D01*
X1074913Y-192397D01*
G01X1092413Y-209897D02*
Y-192397D01*
X1089793Y-195897D01*
G01Y-209897D02*
X1095033D01*
G01X1105765Y-195314D02*
X1107075Y-193564D01*
X1108603Y-192689D01*
X1110350Y-192397D01*
X1112533Y-192980D01*
X1114061Y-194439D01*
X1114498Y-196188D01*
X1114280Y-197939D01*
X1113406Y-199397D01*
X1109040Y-202314D01*
X1107075Y-204355D01*
X1105765Y-207273D01*
X1105328Y-209897D01*
X1114498D01*
G01X1000110Y-164897D02*
Y-147397D01*
X1004476D01*
X1006223Y-148272D01*
X1007533Y-149439D01*
X1008625Y-151188D01*
X1009498Y-153231D01*
X1009716Y-156147D01*
X1009498Y-159064D01*
X1008625Y-161106D01*
X1007533Y-162856D01*
X1006223Y-164022D01*
X1004476Y-164897D01*
X1000110D01*
G01X1026343D02*
Y-153231D01*
G01Y-155272D02*
X1025470Y-154106D01*
X1024159Y-153522D01*
X1022631Y-153231D01*
X1021103Y-153814D01*
X1019793Y-154980D01*
X1018919Y-156730D01*
X1018483Y-159064D01*
X1018919Y-161397D01*
X1019793Y-163147D01*
X1021103Y-164314D01*
X1022631Y-164897D01*
X1024159Y-164605D01*
X1025470Y-163731D01*
X1026343Y-162564D01*
G01X1039913Y-147397D02*
Y-164897D01*
G01X1036856Y-153231D02*
X1042970D01*
G01X1054138Y-157022D02*
X1061125D01*
X1060470Y-154980D01*
X1059378Y-153814D01*
X1057850Y-153231D01*
X1056321Y-153522D01*
X1055011Y-154397D01*
X1054138Y-156439D01*
X1053701Y-158189D01*
Y-159939D01*
X1054138Y-161689D01*
X1055230Y-163439D01*
X1056540Y-164605D01*
X1058068Y-164897D01*
X1059596Y-164314D01*
X1061125Y-162564D01*
G54D12*
X29531Y309549D03*
Y1029510D03*
X17720Y1903132D03*
X271657Y267699D03*
Y673210D03*
Y1078722D03*
Y1484234D03*
Y1889746D03*
X994098Y149588D03*
Y673210D03*
Y1068880D03*
G54D22*
G01X25000Y1357742D02*
X36300Y1346442D01*
Y1052070D01*
X18456Y1034226D01*
Y885899D01*
X28924Y875431D01*
Y861231D01*
X25793Y858100D01*
X25000D01*
G01X331622Y1944767D02*
Y1944766D01*
X280182Y1893326D01*
Y1886214D01*
X266195Y1872227D01*
X137176D01*
X127875Y1862926D01*
X53623D01*
X24274Y1833577D01*
Y1819810D01*
X28897Y1815187D01*
Y1804614D01*
X23024Y1798741D01*
Y1749381D01*
X22025Y1748382D01*
Y1748380D01*
X22024Y1748379D01*
Y1746190D01*
X15850Y1740016D01*
Y1739341D01*
X14884Y1738375D01*
X14018D01*
X12774Y1737131D01*
Y1735369D01*
X14018Y1734125D01*
X14884D01*
X15850Y1733159D01*
Y1726541D01*
X14884Y1725575D01*
X14418D01*
X13174Y1724331D01*
Y1722569D01*
X14418Y1721325D01*
X14884D01*
X15850Y1720359D01*
Y1718152D01*
X19350Y1714652D01*
Y1714651D01*
X38359Y1695642D01*
Y1599273D01*
X43223Y1594409D01*
Y1569515D01*
X37642Y1563934D01*
X34216D01*
X27701Y1557419D01*
Y1545286D01*
X24880Y1542465D01*
Y1534039D01*
X34582Y1524337D01*
X36001D01*
X41274Y1519064D01*
Y859984D01*
X29299Y848009D01*
Y836901D01*
G01X284999Y1947691D02*
Y1935044D01*
X267630Y1917675D01*
X266118D01*
X264874Y1916431D01*
Y1915844D01*
X222907Y1873877D01*
X136491D01*
X127190Y1864576D01*
X52939D01*
X22624Y1834261D01*
Y1819125D01*
X27247Y1814502D01*
Y1805298D01*
X21374Y1799425D01*
Y1750065D01*
X20374Y1749065D01*
Y1746874D01*
X14391Y1740891D01*
X14200D01*
X11124Y1737815D01*
Y1734685D01*
X14200Y1731609D01*
Y1727691D01*
X11524Y1725015D01*
Y1721885D01*
X14200Y1719209D01*
Y1717468D01*
X17700Y1713968D01*
Y1713967D01*
X36709Y1694958D01*
Y1601327D01*
X36708Y1601326D01*
Y1598590D01*
X41573Y1593725D01*
Y1570199D01*
X36958Y1565584D01*
X33529D01*
X31295Y1563350D01*
X25521D01*
G01X30199Y1545450D02*
Y1557583D01*
X34900Y1562284D01*
X38326D01*
X44873Y1568831D01*
Y1595093D01*
X40009Y1599957D01*
Y1696326D01*
X21000Y1715335D01*
Y1715336D01*
X17500Y1718836D01*
Y1739332D01*
X23674Y1745506D01*
Y1747694D01*
X23676Y1747696D01*
Y1747698D01*
X24675Y1748697D01*
Y1750065D01*
X24674Y1750066D01*
Y1798057D01*
X30547Y1803930D01*
Y1819116D01*
X31724Y1820293D01*
Y1829241D01*
X34574Y1832091D01*
Y1839209D01*
X54715Y1859350D01*
X133266D01*
X137242Y1863326D01*
X691775D01*
X777499Y1949050D01*
X792499D01*
G01X33307Y557938D02*
X34199Y557046D01*
Y550150D01*
X35899Y548450D01*
Y538772D01*
X37251Y537420D01*
Y528083D01*
X42150Y523184D01*
Y521750D01*
X42151Y521749D01*
Y511816D01*
X39874Y509539D01*
Y430147D01*
X83746Y386275D01*
X348107D01*
X379474Y417642D01*
Y1117075D01*
X372999Y1123550D01*
G01X284999Y338650D02*
X245099Y378550D01*
X82135D01*
X33274Y427411D01*
Y512060D01*
X30166Y515168D01*
Y535169D01*
X29024Y536311D01*
Y544351D01*
X26199Y547176D01*
G01X377900Y1703800D02*
X383099Y1698601D01*
Y418933D01*
X348791Y384625D01*
X83062D01*
X38224Y429463D01*
Y510224D01*
X40500Y512500D01*
Y522500D01*
X35601Y527399D01*
Y536736D01*
X33974Y538363D01*
Y547543D01*
X29999Y551518D01*
Y557150D01*
G01X390999Y1517798D02*
Y1517050D01*
X388545Y1514596D01*
Y419711D01*
X350159Y381325D01*
X81694D01*
X34924Y428095D01*
Y512744D01*
X31816Y515852D01*
Y535853D01*
X30674Y536995D01*
Y546175D01*
X25581Y551268D01*
Y567763D01*
G01X385499Y1735050D02*
Y418999D01*
X349475Y382975D01*
X82378D01*
X36574Y428779D01*
Y513428D01*
X33466Y516536D01*
Y536537D01*
X32324Y537679D01*
Y546859D01*
X27766Y551417D01*
Y573683D01*
X27699Y573750D01*
G01X35900Y412600D02*
X31624Y416876D01*
Y511376D01*
X28516Y514484D01*
Y533484D01*
X24900Y537100D01*
Y544100D01*
X21174Y547826D01*
Y566307D01*
X24803Y569936D01*
Y605903D01*
X32537Y613637D01*
Y628531D01*
X32535Y628533D01*
Y644793D01*
X32537Y644795D01*
Y646813D01*
X32824Y647100D01*
Y668876D01*
X31100Y670600D01*
Y691376D01*
X31824Y692100D01*
Y699994D01*
X25800Y706018D01*
Y744100D01*
X29575Y747875D01*
Y768225D01*
X25474Y772326D01*
Y801634D01*
X29300Y805460D01*
Y833500D01*
X27474Y835326D01*
Y857446D01*
X30137Y860109D01*
Y860110D01*
X37974Y867947D01*
Y1008210D01*
X20106Y1026078D01*
Y1033542D01*
X37974Y1051410D01*
Y1388026D01*
X34375Y1391624D01*
Y1393534D01*
X33307Y1394602D01*
X31397D01*
X30500Y1395500D01*
G01X33699Y561850D02*
X35849Y559700D01*
Y550834D01*
X37549Y549134D01*
Y539456D01*
X38901Y538104D01*
Y528767D01*
X43800Y523868D01*
Y522434D01*
X43801Y522433D01*
Y512501D01*
X43802Y512500D01*
Y511132D01*
X41524Y508854D01*
Y430831D01*
X84430Y387925D01*
X347423D01*
X377824Y418326D01*
Y881166D01*
X370149Y888841D01*
Y1320050D01*
G01X39217Y554750D02*
X39392Y554575D01*
Y539947D01*
X40551Y538788D01*
Y529451D01*
X45450Y524552D01*
Y523118D01*
X45451Y523117D01*
Y513185D01*
X45452Y513184D01*
Y510448D01*
X43174Y508170D01*
Y431515D01*
X84939Y389750D01*
X345867D01*
X375999Y419882D01*
Y698550D01*
G01X36499Y566350D02*
X46024Y556825D01*
Y555807D01*
X48801Y553030D01*
Y532871D01*
X53700Y527972D01*
Y526538D01*
X53701Y526537D01*
Y516605D01*
X53702Y516604D01*
Y507028D01*
X51424Y504750D01*
Y449236D01*
X98335Y402325D01*
X345431D01*
X364499Y421393D01*
Y1099050D01*
G01X141499Y423050D02*
X130349Y434200D01*
X90525D01*
X82725Y442000D01*
X69343D01*
X56374Y454969D01*
Y502698D01*
X58652Y504976D01*
Y530022D01*
X53751Y534923D01*
Y562360D01*
X48011Y568100D01*
X45443D01*
X36174Y577369D01*
Y616274D01*
X44900Y625000D01*
Y630154D01*
X47101Y632355D01*
G01X28000Y578500D02*
Y577448D01*
X33899Y571550D01*
Y566050D01*
X41042Y558907D01*
Y540631D01*
X42201Y539472D01*
Y530135D01*
X47100Y525236D01*
Y523802D01*
X47101Y523801D01*
Y513869D01*
X47102Y513868D01*
Y509764D01*
X44824Y507486D01*
Y432199D01*
X85623Y391400D01*
X345183D01*
X373824Y420041D01*
Y878276D01*
X371500Y880600D01*
G01X39600Y626984D02*
X36435Y630149D01*
Y643074D01*
X37480Y644119D01*
Y666680D01*
X40500Y669700D01*
Y696834D01*
X29700Y707634D01*
Y741600D01*
X33475Y745375D01*
Y785725D01*
X32200Y787000D01*
Y796400D01*
X44571Y808771D01*
Y846094D01*
X53424Y854947D01*
Y1527165D01*
X76950Y1550691D01*
Y1560250D01*
X78600Y1561900D01*
G01X42709Y625607D02*
X42136Y625034D01*
X38792D01*
X34485Y629341D01*
Y643985D01*
X35300Y644800D01*
Y668600D01*
X38300Y671600D01*
Y696276D01*
X27750Y706826D01*
Y743292D01*
X31076Y746618D01*
X31077D01*
X31525Y747067D01*
Y784775D01*
X29600Y786700D01*
Y796558D01*
X42621Y809579D01*
Y846902D01*
X51474Y855755D01*
Y1527974D01*
X75000Y1551500D01*
Y1561800D01*
G01X38300Y633800D02*
X39209Y634709D01*
Y643090D01*
X42019Y645900D01*
X65433D01*
X201957Y782424D01*
X324704D01*
X351024Y808744D01*
Y1530376D01*
X349774Y1531626D01*
Y1582900D01*
G01X381999Y57050D02*
X404474Y79525D01*
Y1729109D01*
X345683Y1787900D01*
X141068D01*
X123381Y1805587D01*
X76047D01*
X60349Y1789889D01*
Y1769385D01*
X46789Y1755825D01*
X41518D01*
X40450Y1754757D01*
Y1754755D01*
X34576Y1748881D01*
Y1744594D01*
X33575Y1743593D01*
Y1743591D01*
X33574Y1743590D01*
Y1741402D01*
X27400Y1735228D01*
Y1722940D01*
X30900Y1719440D01*
Y1719439D01*
X53123Y1697216D01*
Y1565409D01*
X39199Y1551485D01*
Y1540316D01*
X34524Y1535641D01*
Y1528148D01*
X42924Y1519748D01*
Y859299D01*
X33624Y849999D01*
Y807450D01*
X27124Y800950D01*
Y783725D01*
X27299Y783550D01*
G01X32800Y803050D02*
X35274Y805524D01*
Y849315D01*
X44574Y858615D01*
Y1520432D01*
X36174Y1528832D01*
Y1534957D01*
X40849Y1539632D01*
Y1550800D01*
X54773Y1564724D01*
Y1697900D01*
X32550Y1720123D01*
Y1720124D01*
X29050Y1723624D01*
Y1734544D01*
X35224Y1740718D01*
Y1742906D01*
X35225Y1742907D01*
Y1742909D01*
X36226Y1743910D01*
Y1744007D01*
X39375Y1747156D01*
Y1747807D01*
X41118Y1749550D01*
X47518D01*
X67643Y1769675D01*
X301523D01*
X360307Y1710891D01*
Y772858D01*
X327999Y740550D01*
G01X74500Y1692000D02*
X73654D01*
X63023Y1681369D01*
Y1546950D01*
X46224Y1530151D01*
Y857931D01*
X36925Y848632D01*
Y814106D01*
X38924Y812107D01*
Y809659D01*
X37216Y807951D01*
G01X39649Y822000D02*
X38575Y823074D01*
Y847948D01*
X47874Y857247D01*
Y1529467D01*
X65163Y1546756D01*
Y1575063D01*
X74800Y1584700D01*
G01X29600Y854000D02*
X39624Y864024D01*
Y1513506D01*
X33459Y1519671D01*
X28228D01*
X24199Y1523700D01*
G01X37999Y1530900D02*
X61373Y1554274D01*
Y1683373D01*
X92400Y1714400D01*
X101787D01*
X104000Y1716613D01*
X112753D01*
G01X200799Y896600D02*
Y903785D01*
X310898Y1013884D01*
Y1066450D01*
X313000Y1068553D01*
X337124Y1092677D01*
Y1611632D01*
X186031Y1762725D01*
X141242D01*
X140243Y1763724D01*
X68697D01*
X49573Y1744600D01*
X44317D01*
X43292Y1743575D01*
X40559D01*
X38525Y1741541D01*
Y1741539D01*
X38524Y1741538D01*
Y1739350D01*
X32350Y1733176D01*
Y1724992D01*
X58074Y1699268D01*
Y1697900D01*
X58073Y1697899D01*
Y1562143D01*
X45055Y1549125D01*
X44448D01*
X42499Y1547176D01*
Y1538599D01*
X38500Y1534600D01*
G01X32099Y1535550D02*
X37549Y1541000D01*
Y1552169D01*
X51473Y1566093D01*
Y1696532D01*
X29250Y1718755D01*
Y1718756D01*
X25750Y1722256D01*
Y1735912D01*
X31924Y1742086D01*
Y1744274D01*
X31925Y1744275D01*
Y1744277D01*
X32926Y1745278D01*
Y1749566D01*
X38800Y1755440D01*
Y1755441D01*
X40834Y1757475D01*
X40835D01*
X42926Y1759566D01*
X48196D01*
X58699Y1770069D01*
Y1813140D01*
X68083Y1822524D01*
X512525D01*
X791499Y1543550D01*
G01X26705Y1534795D02*
X35899Y1543989D01*
Y1548747D01*
X35898Y1548748D01*
Y1552852D01*
X49823Y1566777D01*
Y1695848D01*
X27600Y1718071D01*
Y1718072D01*
X24100Y1721572D01*
Y1736596D01*
X30274Y1742770D01*
Y1744958D01*
X30275Y1744959D01*
Y1744961D01*
X31276Y1745962D01*
Y1751394D01*
X43307Y1763425D01*
X48156D01*
X57049Y1772318D01*
Y1813848D01*
X72948Y1829747D01*
X543142D01*
X860652Y1512237D01*
Y1432606D01*
X769208Y1341162D01*
Y1142007D01*
X770024Y1141191D01*
Y1129944D01*
X771743Y1128225D01*
X773255D01*
X783405Y1138375D01*
X789174D01*
X789499Y1138050D01*
G01X36340Y1558809D02*
X39521D01*
X48173Y1567461D01*
Y1695164D01*
X25950Y1717387D01*
Y1717388D01*
X22450Y1720888D01*
Y1737280D01*
X28624Y1743454D01*
Y1745642D01*
X28625Y1745643D01*
Y1745645D01*
X29626Y1746646D01*
Y1750749D01*
X29625Y1750750D01*
Y1752117D01*
X29624Y1752118D01*
Y1774275D01*
X40199Y1784850D01*
Y1792959D01*
X42353Y1795113D01*
Y1798504D01*
X47601Y1803752D01*
Y1818515D01*
X67461Y1838375D01*
X154997D01*
X156175Y1837197D01*
X550358D01*
X904844Y1482711D01*
Y903395D01*
X788999Y787550D01*
Y736050D01*
G01X789999Y336550D02*
Y423050D01*
X911444Y544495D01*
Y1495611D01*
X560305Y1846750D01*
X135630D01*
X134205Y1848175D01*
X63493D01*
X56000Y1840682D01*
Y1836250D01*
X41001Y1821251D01*
Y1808944D01*
X27974Y1795917D01*
Y1751434D01*
X27975Y1751433D01*
Y1750066D01*
X27976Y1750065D01*
Y1747330D01*
X26975Y1746329D01*
Y1746327D01*
X26974Y1746326D01*
Y1744138D01*
X20800Y1737964D01*
Y1720204D01*
X24300Y1716704D01*
Y1716703D01*
X46523Y1694480D01*
Y1568145D01*
X39011Y1560633D01*
X37644D01*
X37643Y1560634D01*
X35584D01*
X34515Y1559565D01*
Y1556111D01*
X34896Y1555730D01*
G01X30500Y1697500D02*
X31000Y1697000D01*
Y1675000D01*
X32700Y1673300D01*
G01X967600Y1651100D02*
Y1682396D01*
X801396Y1848600D01*
X136114D01*
X134889Y1849825D01*
X62809D01*
X49418Y1836434D01*
Y1834818D01*
X32197Y1817597D01*
Y1803246D01*
X26324Y1797373D01*
Y1750750D01*
X26325Y1750749D01*
Y1749382D01*
X26326Y1749381D01*
Y1748014D01*
X25325Y1747013D01*
Y1747011D01*
X25324Y1747010D01*
Y1744822D01*
X19150Y1738648D01*
Y1719520D01*
X22650Y1716020D01*
Y1716019D01*
X42199Y1696470D01*
Y1601050D01*
G01X106718Y1076050D02*
X116468Y1085800D01*
X126291D01*
X128350Y1083741D01*
Y1067141D01*
X131116Y1064375D01*
X161498D01*
X196000Y1098877D01*
Y1172217D01*
X328325Y1304542D01*
Y1611009D01*
X184984Y1754350D01*
X102550D01*
X95225Y1761675D01*
X68983D01*
X50258Y1742950D01*
X45002D01*
X43977Y1741925D01*
X41243D01*
X40175Y1740857D01*
Y1740855D01*
X40174Y1740854D01*
Y1738666D01*
X34000Y1732492D01*
Y1725676D01*
X59724Y1699952D01*
Y1697216D01*
X59723Y1697215D01*
Y1561459D01*
X45057Y1546793D01*
X44697D01*
G01X282099Y745050D02*
Y761156D01*
X297343Y776400D01*
X325934D01*
X357007Y807473D01*
Y1709523D01*
X300155Y1766375D01*
X69013D01*
X48888Y1746250D01*
X43632D01*
X42608Y1745226D01*
X41958D01*
X41957Y1745225D01*
X39875D01*
X36875Y1742225D01*
Y1742223D01*
X36874Y1742222D01*
Y1740034D01*
X30700Y1733860D01*
Y1724308D01*
X34200Y1720808D01*
Y1720807D01*
X56423Y1698584D01*
Y1563074D01*
X44299Y1550950D01*
G01X350499Y715050D02*
X361957Y726508D01*
Y1711575D01*
X298294Y1775238D01*
X70871D01*
X46833Y1751200D01*
X39900D01*
G01X854400Y264600D02*
X849950Y269050D01*
X818888D01*
X791499Y296439D01*
Y322050D01*
X770353Y343196D01*
Y405738D01*
X909794Y545179D01*
Y1489914D01*
X839783Y1559925D01*
X839018D01*
X553843Y1845100D01*
X134945D01*
X133520Y1846525D01*
X68609D01*
X42651Y1820567D01*
Y1808260D01*
X33924Y1799533D01*
Y1796393D01*
X29986Y1792455D01*
Y1787526D01*
X30274Y1787238D01*
G01X37699Y1789850D02*
X35749Y1791800D01*
Y1799024D01*
X44301Y1807576D01*
Y1819883D01*
X69293Y1844875D01*
X132836D01*
X134261Y1843450D01*
X553159D01*
X838334Y1558275D01*
X839099D01*
X908144Y1489230D01*
Y545863D01*
X768703Y406422D01*
Y337550D01*
X772873Y333380D01*
Y326924D01*
G01X36532Y1825352D02*
X34574Y1827310D01*
Y1829757D01*
X36224Y1831407D01*
Y1838525D01*
X55399Y1857700D01*
X142149D01*
X146121Y1861672D01*
X693121D01*
X771499Y1940050D01*
G01X36399Y1828750D02*
X37874Y1830225D01*
Y1837841D01*
X55108Y1855075D01*
X139974D01*
X141202Y1853847D01*
X144796D01*
X150499Y1859550D01*
X830814D01*
X854814Y1883550D01*
G01X29599Y1844350D02*
X29899Y1844650D01*
X30678D01*
X52254Y1866226D01*
X126506D01*
X135807Y1875527D01*
X215828D01*
X227814Y1887513D01*
G01X28123Y1831527D02*
X32924Y1836328D01*
Y1839893D01*
X54031Y1861000D01*
X128283D01*
X137860Y1870577D01*
X271107D01*
X333447Y1932917D01*
Y1946789D01*
X332103Y1948133D01*
G01X971558Y1646500D02*
Y1683116D01*
X802477Y1852197D01*
X137517D01*
X136589Y1853125D01*
X55492D01*
X40699Y1838332D01*
Y1834850D01*
X39699Y1833850D01*
G01X371999Y549300D02*
Y420550D01*
X344499Y393050D01*
X86307D01*
X46474Y432883D01*
Y506802D01*
X48752Y509080D01*
Y514552D01*
X48751Y514553D01*
Y524485D01*
X48750Y524486D01*
Y525920D01*
X43851Y530819D01*
Y547466D01*
X42867Y548450D01*
G01X43099Y555850D02*
Y552584D01*
X45501Y550182D01*
Y531503D01*
X50400Y526604D01*
Y525170D01*
X50401Y525169D01*
Y515237D01*
X50402Y515236D01*
Y508396D01*
X48124Y506118D01*
Y433567D01*
X82666Y399025D01*
X346799D01*
X367974Y420200D01*
Y1742575D01*
X348499Y1762050D01*
G01X46299Y552950D02*
Y551718D01*
X47151Y550866D01*
Y532187D01*
X52050Y527288D01*
Y525854D01*
X52051Y525853D01*
Y515921D01*
X52052Y515920D01*
Y507712D01*
X49774Y505434D01*
Y434265D01*
X83364Y400675D01*
X346115D01*
X366324Y420884D01*
Y1553875D01*
X366149Y1554050D01*
G01X285499Y745050D02*
X346345Y684204D01*
Y405573D01*
X344747Y403975D01*
X99019D01*
X53074Y449920D01*
Y504066D01*
X55352Y506344D01*
Y517288D01*
X55351Y517289D01*
Y527221D01*
X55350Y527222D01*
Y528656D01*
X50451Y533555D01*
Y553714D01*
X47699Y556466D01*
Y562400D01*
X42599Y567500D01*
Y567850D01*
G01X344520Y406329D02*
X98999D01*
X54724Y450604D01*
Y503382D01*
X57002Y505660D01*
Y517972D01*
X57001Y517973D01*
Y529339D01*
X52101Y534239D01*
Y556848D01*
X49799Y559150D01*
G01X68000Y546500D02*
X71500Y543000D01*
X91055D01*
X95924Y538131D01*
Y528724D01*
X73700Y506500D01*
X68643D01*
X58422Y496279D01*
Y455927D01*
X61400Y452949D01*
Y452600D01*
G01X72500Y545000D02*
X91389D01*
X97574Y538815D01*
Y527553D01*
X60072Y490051D01*
Y461528D01*
X65000Y456600D01*
Y455500D01*
G01X47626Y611300D02*
X49026Y609900D01*
X71100D01*
X78700Y602300D01*
X104500D01*
X107000Y604800D01*
G01X104893Y599793D02*
X78449D01*
X70542Y607700D01*
X45701D01*
G01X354000Y1584900D02*
X354024Y1584876D01*
Y1568000D01*
X352674Y1566650D01*
Y809428D01*
X352675Y809427D01*
Y808061D01*
X325388Y780774D01*
X202642D01*
X66668Y644800D01*
X66667D01*
X66117Y644250D01*
X50349D01*
X48999Y642900D01*
G01D02*
Y638501D01*
X52500Y635000D01*
G01X46887Y803413D02*
X49275Y805801D01*
Y807057D01*
X52200Y809982D01*
Y817883D01*
X52598Y818281D01*
Y845420D01*
X58925Y851747D01*
Y1041307D01*
X111608Y1093990D01*
X120749D01*
G01X65500Y817700D02*
X45100Y797300D01*
Y793100D01*
G01X326500Y1550200D02*
Y1305051D01*
X194350Y1172901D01*
Y1099561D01*
X160814Y1066025D01*
X132307D01*
X130000Y1068332D01*
Y1084425D01*
X126975Y1087450D01*
X110231D01*
X106756Y1083975D01*
X106343D01*
X60575Y1038207D01*
Y851063D01*
X54249Y844737D01*
Y815925D01*
X54074Y815750D01*
G01X46576Y832951D02*
X46521Y833006D01*
Y845286D01*
X55374Y854139D01*
Y1410226D01*
X76000Y1430852D01*
Y1431100D01*
G01X131999Y1710050D02*
X134915Y1707134D01*
Y1622960D01*
X90355Y1578400D01*
X84453D01*
X67121Y1561068D01*
Y1546379D01*
X49524Y1528782D01*
Y856563D01*
X40400Y847439D01*
Y840792D01*
G01X48346Y844529D02*
X57275Y853458D01*
Y1156813D01*
X60502Y1160040D01*
Y1160042D01*
X106162Y1205702D01*
G01X76000Y1431100D02*
X55424Y1451676D01*
Y1525323D01*
X85600Y1555499D01*
Y1561500D01*
G01X89373Y1561073D02*
Y1556938D01*
X57074Y1524639D01*
Y1452608D01*
X77825Y1431857D01*
Y1430343D01*
X63023Y1415541D01*
Y1372477D01*
X77758Y1357742D01*
G01X225298Y281114D02*
X288543D01*
X396199Y388770D01*
Y406697D01*
X396474Y406972D01*
Y1728990D01*
X342589Y1782875D01*
X76174D01*
X47299Y1754000D01*
X42275D01*
G01X41200Y1747050D02*
X41850D01*
X42700Y1747900D01*
X48203D01*
X68328Y1768025D01*
X300839D01*
X358657Y1710207D01*
Y774958D01*
X327749Y744050D01*
G01X47400Y1765250D02*
X55399Y1773249D01*
Y1816730D01*
X61009Y1822340D01*
G01X47899Y1798650D02*
X50901Y1801652D01*
Y1817147D01*
X66801Y1833047D01*
X544510D01*
X901544Y1476013D01*
Y1121912D01*
X857348Y1077716D01*
X852333D01*
G01X42199Y1792250D02*
X44667Y1794718D01*
Y1798418D01*
X49251Y1803002D01*
Y1817831D01*
X66117Y1834697D01*
X545194D01*
X903194Y1476697D01*
Y904079D01*
X769071Y769956D01*
Y742144D01*
X769999Y741216D01*
Y733050D01*
G01X772499Y1130050D02*
Y1160052D01*
X773458Y1161011D01*
Y1343009D01*
X865524Y1435075D01*
Y1509699D01*
X543826Y1831397D01*
X67485D01*
X52551Y1816463D01*
Y1800652D01*
X46799Y1794900D01*
G01X40478Y1795820D02*
X40703Y1796045D01*
Y1799854D01*
X45951Y1805102D01*
Y1819199D01*
X66777Y1840025D01*
X155681D01*
X156859Y1838847D01*
X552342D01*
X834564Y1556625D01*
X838415D01*
X906494Y1488546D01*
Y721324D01*
X856367Y671197D01*
X852696D01*
G01X969600Y1638300D02*
Y1682740D01*
X802090Y1850250D01*
X137129D01*
X135904Y1851475D01*
X56176D01*
X43099Y1838398D01*
Y1833850D01*
G01X76540Y850938D02*
X76045Y851433D01*
Y854907D01*
X74586Y856366D01*
Y975286D01*
X90000Y990700D01*
Y993100D01*
G01X75500Y847700D02*
Y849220D01*
X72395Y852325D01*
Y976555D01*
X88050Y992210D01*
Y993908D01*
X90242Y996100D01*
X92600D01*
G01X65486Y1031515D02*
X65500Y1031529D01*
Y1031551D01*
X103449Y1069500D01*
X105600D01*
G01X326499Y337454D02*
X392824Y403779D01*
Y1730306D01*
X343905Y1779225D01*
X200742D01*
X199451Y1780516D01*
X76816D01*
X74400Y1778100D01*
G01X381999Y53550D02*
X406124Y77675D01*
Y1729793D01*
X316693Y1819224D01*
X99167D01*
X95218Y1815275D01*
X82074D01*
X80099Y1817250D01*
G01X282800Y87500D02*
Y93249D01*
X231999Y144050D01*
X116124D01*
X97499Y125425D01*
Y90050D01*
G01X82499Y627050D02*
X90650D01*
X124600Y661000D01*
X165000D01*
X165618Y660382D01*
Y594669D01*
X158999Y588050D01*
Y512050D01*
X170499Y500550D01*
Y490201D01*
X176200Y484500D01*
X188000D01*
G01X89000Y816500D02*
X87675Y817825D01*
Y831256D01*
X94469Y838050D01*
X154799D01*
G01X90000Y826000D02*
X130100D01*
X143225Y812875D01*
X191630D01*
X337499Y958744D01*
Y1054550D01*
X343674Y1060725D01*
Y1097307D01*
X345424Y1099057D01*
Y1310050D01*
G01X153500Y834600D02*
X153400D01*
X151625Y836375D01*
X98475D01*
X97425Y835325D01*
X97243D01*
X96175Y834257D01*
Y834075D01*
X93600Y831500D01*
X90500D01*
G01X94999Y901550D02*
X111999Y918550D01*
X153499D01*
G01X157400Y1596550D02*
X97499Y1554550D01*
G01X96999Y1558050D02*
X156000Y1598500D01*
X160200D01*
G01X330300Y1561200D02*
Y1613788D01*
X188088Y1756000D01*
X105098D01*
X99199Y1761899D01*
G01X123999Y1102550D02*
X129400Y1097149D01*
Y1090500D01*
X132000Y1087900D01*
Y1068666D01*
X132991Y1067675D01*
X160130D01*
X192699Y1100244D01*
Y1173585D01*
X324600Y1305486D01*
Y1551200D01*
X326074Y1552674D01*
Y1610926D01*
X184450Y1752550D01*
X101024D01*
X99999Y1753575D01*
G01X101399Y1784700D02*
X118015D01*
X118116Y1784599D01*
X343199D01*
X398124Y1729674D01*
Y406288D01*
X397849Y406013D01*
Y197900D01*
X297499Y97550D01*
G01X402499Y1476850D02*
X402399Y1476950D01*
Y1574368D01*
X402824Y1574793D01*
Y1576307D01*
X402399Y1576732D01*
Y1728850D01*
X344999Y1786250D01*
X118799D01*
X107699Y1797350D01*
X85599D01*
G01X96600Y1826000D02*
X98697Y1828097D01*
X542458D01*
X854327Y1516228D01*
Y1477550D01*
G01X86649Y1817100D02*
X90423Y1820874D01*
X495395D01*
X774577Y1541692D01*
Y1533796D01*
G01X135499Y517550D02*
X131499D01*
X129924Y515975D01*
X129908D01*
X110983Y497050D01*
X107499D01*
G01X107000Y604800D02*
X107800Y604000D01*
Y591900D01*
X106000Y590100D01*
Y546600D01*
X109400Y543200D01*
G01X104893Y599793D02*
X103700Y598600D01*
Y545500D01*
X106000Y543200D01*
G01X105100Y600000D02*
X104893Y599793D01*
G01X111100Y813400D02*
X110800D01*
X104075Y806675D01*
Y791010D01*
X109260Y785825D01*
X325771D01*
X349149Y809203D01*
Y1529917D01*
X346974Y1532092D01*
Y1703925D01*
X353499Y1710450D01*
G01X111200Y799450D02*
X118225Y792425D01*
X320374D01*
X329499Y801550D01*
G01X347324Y1524000D02*
Y809712D01*
X325087Y787475D01*
X109944D01*
X105725Y791694D01*
Y804519D01*
X111207Y810001D01*
G01X110500Y790200D02*
X111575Y789125D01*
X324074D01*
X330458Y795509D01*
X330540D01*
G01X110800Y803100D02*
X109516D01*
X107375Y800959D01*
Y796444D01*
X113044Y790775D01*
X321305D01*
X345499Y814969D01*
Y1096550D01*
G01X110700Y795700D02*
Y795800D01*
X109025Y797475D01*
Y800275D01*
X110025Y801275D01*
X113625D01*
X116850Y798050D01*
X320499D01*
G01X111089Y806603D02*
X111397D01*
X114112Y803888D01*
X190288D01*
X203100Y816700D01*
Y822011D01*
X339149Y958060D01*
Y1044536D01*
X340699Y1046086D01*
G01X165499Y815550D02*
X146499Y834550D01*
X110499D01*
G01X112699Y1058974D02*
X112225Y1058500D01*
X112000D01*
X105624Y1052124D01*
Y1003425D01*
X149049Y960000D01*
X152500D01*
G01X116700Y1063500D02*
Y1014617D01*
X169767Y961550D01*
X171450D01*
X172000Y961000D01*
G01X123970Y1221573D02*
X125522D01*
X179499Y1275550D01*
G01X110099Y1759875D02*
X186547D01*
X335474Y1610948D01*
Y1095519D01*
X174955Y935000D01*
X171100D01*
G01X199900Y554050D02*
Y491951D01*
X197124Y489175D01*
Y489169D01*
X155330Y447375D01*
X153344D01*
X152276Y446307D01*
Y444327D01*
X141499Y433550D01*
Y427550D01*
G01X141999Y1764550D02*
X186541D01*
X340624Y1610467D01*
Y1093843D01*
X315304Y1068523D01*
X312548Y1065766D01*
Y962248D01*
X169106Y818806D01*
Y815865D01*
G01X220000Y516400D02*
X216763D01*
X212999Y512636D01*
Y500550D01*
X159600Y447151D01*
Y446399D01*
G01X150999Y1713550D02*
X151950D01*
X171999Y1693501D01*
Y1662250D01*
G01X354500Y1559500D02*
Y1532049D01*
X355357Y1531192D01*
Y808157D01*
X325250Y778050D01*
X296659D01*
X177579Y658970D01*
Y501550D01*
X172499Y496470D01*
Y491053D01*
G01X183499Y556100D02*
X283124Y655725D01*
Y725425D01*
X279939Y728610D01*
G01X257499Y1911050D02*
Y1927056D01*
X288993Y1958550D01*
X308999D01*
X310499Y1957050D01*
G01X390999Y1514398D02*
Y419831D01*
X306993Y335825D01*
X284224D01*
X281499Y338550D01*
G01X394649Y630600D02*
Y407481D01*
X394474Y407306D01*
Y402029D01*
X326499Y334054D01*
G01X400999Y1575550D02*
Y1575302D01*
X400674Y1574977D01*
Y1464475D01*
X402499Y1462650D01*
Y196965D01*
G02X402323Y196540I-601J0D01*
G01X343874Y138091D01*
Y65425D01*
X341499Y63050D01*
G01Y67110D02*
Y138050D01*
X399499Y196050D01*
Y405329D01*
X400499Y406329D01*
G01X900499Y962100D02*
X897536D01*
X779499Y1080137D01*
Y1131050D01*
G01X780499Y330050D02*
Y277050D01*
X837999Y219550D01*
G01X902999Y556050D02*
X885740D01*
X780874Y660916D01*
Y700431D01*
X781999Y701556D01*
Y725550D01*
G54D13*
X14999Y1936050D03*
Y1940050D03*
X8499Y1937550D03*
X15099Y1944050D03*
X5303Y1947050D03*
X11703Y1951946D03*
X17499Y1961050D03*
X29699Y388484D03*
X29599Y382884D03*
X23399Y373931D03*
Y389679D03*
X23499Y381831D03*
X26299Y383854D03*
Y387629D03*
X28100Y374000D03*
X26299Y399601D03*
Y403376D03*
X29999Y398684D03*
X29899Y404384D03*
X23799Y405684D03*
X23499Y397579D03*
X35900Y412600D03*
X26524Y426720D03*
X26399Y423322D03*
X28672Y429356D03*
X29365Y421169D03*
X23399Y429051D03*
X28900Y417800D03*
X26492Y439350D03*
X26599Y442749D03*
X26899Y454850D03*
X28700Y451900D03*
X28800Y436700D03*
X28700Y445700D03*
X23399Y444799D03*
X23499Y452699D03*
Y436951D03*
X26799Y458497D03*
X26486Y462648D03*
X26499Y466250D03*
X29500Y460800D03*
X23499Y468447D03*
X23399Y476295D03*
Y460547D03*
X26299Y478404D03*
X26515Y481798D03*
X23399Y492043D03*
X23499Y484195D03*
X36499Y517775D03*
X26399Y501966D03*
Y505741D03*
X28600Y508500D03*
X38400Y514955D03*
X28664Y499429D03*
X23499Y515691D03*
Y499943D03*
X23399Y507791D03*
X36499Y521550D03*
X35338Y524746D03*
X26691Y532701D03*
X22800Y539600D03*
X23399Y523539D03*
X23499Y531439D03*
X26599Y525648D03*
Y529302D03*
X27199Y539600D03*
X39217Y554750D03*
X33307Y557938D03*
X26199Y547176D03*
X29999Y557150D03*
X33699Y561850D03*
X36499Y566350D03*
X22699Y577950D03*
X22999Y565550D03*
X28000Y578500D03*
X25581Y567763D03*
X27699Y573750D03*
X22978Y588571D03*
X28808Y593150D03*
X28700Y596549D03*
X27499Y620203D03*
Y623857D03*
X37999Y611550D03*
X26869Y616861D03*
X23499Y618053D03*
X23999Y609250D03*
X34976Y619250D03*
X26800Y611500D03*
X32200Y603710D03*
X31598Y607102D03*
X39600Y626984D03*
X38300Y633800D03*
X30712Y624971D03*
X29999Y640550D03*
X29819Y634951D03*
X23399Y641649D03*
X23799Y625950D03*
X23499Y633801D03*
X26568Y635950D03*
Y639604D03*
X30999Y656250D03*
Y650550D03*
X23499Y665297D03*
Y649549D03*
X23725Y657471D03*
X26737Y651957D03*
X26999Y656550D03*
X23699Y673150D03*
X23499Y681045D03*
X27687Y667447D03*
Y671101D03*
X27700Y682700D03*
X29999Y694550D03*
X25999Y694870D03*
X23999Y689050D03*
X27299Y783550D03*
X35300Y789375D03*
X32800Y803050D03*
X37416Y799033D03*
X37099Y811350D03*
X26299Y815050D03*
X35559Y795112D03*
X31699Y814350D03*
X37216Y807951D03*
X39649Y822000D03*
X29299Y836901D03*
X40400Y840792D03*
X22500Y853700D03*
X29600Y854000D03*
X23299Y863050D03*
X26662Y861550D03*
X25000Y858100D03*
X20400Y1048300D03*
X20999Y1320550D03*
X23700Y1354600D03*
X20999Y1352050D03*
X25000Y1357742D03*
X22851Y1374169D03*
X22999Y1366050D03*
X23499Y1381550D03*
X25507Y1372045D03*
X25558Y1368447D03*
X32550Y1392777D03*
X27499Y1387550D03*
X24499Y1389663D03*
X28499Y1391050D03*
X32333Y1389383D03*
X30500Y1395500D03*
X33321Y1414755D03*
X29786Y1414858D03*
X23499Y1421550D03*
X23999Y1413550D03*
X32451Y1411468D03*
X28999Y1411550D03*
X32094Y1448448D03*
X28697Y1448296D03*
X36198Y1446749D03*
X27099Y1444350D03*
X30999Y1438050D03*
X27999Y1430050D03*
X23499Y1445050D03*
X22999Y1437050D03*
X23999Y1429050D03*
X33206Y1432352D03*
X30499Y1434550D03*
X30378Y1462518D03*
X33915Y1462681D03*
X29069Y1459379D03*
X36791Y1460866D03*
X23028Y1468579D03*
X23499Y1460550D03*
X22999Y1453050D03*
X34465Y1481683D03*
X30999Y1482050D03*
X32520Y1485092D03*
X28999Y1478050D03*
X23599Y1476350D03*
X23277Y1484050D03*
X34099Y1497550D03*
X30499D03*
X27499Y1495050D03*
X36999Y1494550D03*
X22999Y1500050D03*
X23799Y1508050D03*
X24499Y1492050D03*
X30115Y1511900D03*
X33512Y1512051D03*
X29631Y1533063D03*
X31999Y1517846D03*
Y1521500D03*
X35245Y1522512D03*
X35999Y1514550D03*
X29765Y1515282D03*
X24423Y1527123D03*
X22999Y1515550D03*
X37999Y1530900D03*
X24199Y1523700D03*
X25247Y1546912D03*
X38500Y1534600D03*
X32099Y1535550D03*
X26705Y1534795D03*
X30199Y1545450D03*
X36340Y1558809D03*
X34896Y1555730D03*
X38208Y1569841D03*
X25521Y1563350D03*
X30520Y1572049D03*
X24999Y1569550D03*
X31149Y1568300D03*
X23608Y1572653D03*
X24323Y1559950D03*
X27123Y1572205D03*
X39000Y1573500D03*
X34999Y1595350D03*
X22699Y1594224D03*
X31099Y1595350D03*
X28899Y1613524D03*
X32299D03*
X26999Y1610550D03*
X34884Y1615734D03*
X23499Y1618050D03*
Y1610050D03*
Y1602050D03*
X33599Y1600200D03*
X29499Y1630050D03*
X32199Y1633124D03*
X34816Y1630953D03*
X22999Y1626050D03*
X23499Y1634050D03*
X32663Y1628181D03*
X31999Y1661127D03*
X28600Y1661039D03*
X29626Y1645002D03*
X33026Y1645051D03*
X27499Y1657050D03*
X32989Y1648451D03*
X26785Y1642089D03*
X23499Y1657050D03*
X23999Y1649550D03*
X23415Y1641634D03*
X34699Y1663300D03*
X22999Y1665550D03*
X24244Y1681868D03*
X22864Y1673550D03*
X32700Y1673300D03*
X32494Y1669706D03*
X29100Y1669500D03*
X30500Y1697500D03*
X39900Y1751200D03*
X41200Y1747050D03*
X30274Y1787238D03*
X35675Y1783450D03*
X39324Y1780623D03*
X38094Y1785840D03*
X38878Y1799571D03*
X34599Y1805123D03*
X37699Y1789850D03*
X37574Y1794050D03*
X31811Y1790271D03*
X40478Y1795820D03*
X32099Y1797150D03*
X28550Y1828153D03*
X29899Y1821050D03*
X34099Y1822850D03*
X35876Y1812350D03*
X34129Y1815267D03*
X36532Y1825352D03*
X36399Y1828750D03*
X26099Y1824950D03*
X29599Y1844350D03*
X22099Y1836609D03*
X28123Y1831527D03*
X25999Y1842550D03*
X39699Y1833850D03*
X28799Y1919060D03*
X23030Y1922038D03*
X26765Y1921945D03*
X34799Y1946750D03*
X38703Y1946754D03*
X25499Y1956050D03*
X32999Y1960555D03*
X31799Y1979050D03*
X41999Y200050D03*
X45800Y405200D03*
X61400Y452600D03*
X62497Y474346D03*
X60003Y534150D03*
X59999Y537550D03*
X42867Y548450D03*
X43099Y555850D03*
X46299Y552950D03*
X49799Y559150D03*
X42599Y567850D03*
X47543Y578340D03*
X44959Y575756D03*
X60076Y595777D03*
X55499Y595650D03*
X42202Y608195D03*
X41400Y611500D03*
X47626Y611300D03*
X45701Y607700D03*
X42709Y625607D03*
X41500Y642800D03*
X57800Y634300D03*
X44900Y642800D03*
X47101Y632355D03*
X41500Y635000D03*
X52500D03*
X48999Y642900D03*
X50410Y695801D03*
X50300Y699200D03*
X45100Y793100D03*
X44046Y799554D03*
X46887Y803413D03*
X51100Y806300D03*
X49900Y813200D03*
X56281Y801350D03*
X50399Y836250D03*
X46700Y820100D03*
X54074Y815750D03*
X62405Y820300D03*
X46576Y832951D03*
X48346Y844529D03*
X58699Y837250D03*
X44697Y1546793D03*
X44299Y1550950D03*
X42199Y1601050D03*
X47400Y1721700D03*
X42000Y1740100D03*
X47717Y1731337D03*
X47800Y1740500D03*
X45877Y1728477D03*
Y1724823D03*
X47000Y1737100D03*
X43600D03*
X42275Y1754000D03*
X45799Y1757650D03*
X47440Y1761391D03*
X47400Y1765250D03*
X43751Y1780559D03*
X46999Y1779550D03*
X46199Y1783050D03*
X43925Y1767890D03*
X47604Y1769005D03*
X45782Y1771877D03*
X47499Y1775350D03*
X47899Y1798650D03*
X48049Y1791450D03*
X42199Y1792250D03*
X46799Y1794900D03*
X61009Y1822340D03*
X60449Y1842550D03*
X46499Y1836550D03*
X47166Y1839884D03*
X43099Y1833850D03*
X57999Y1891050D03*
X42499Y1902550D03*
X48499Y1897050D03*
X44368Y1951450D03*
X44399Y1942250D03*
X42532Y1946783D03*
X53999Y1946650D03*
X50299D03*
X46565Y1946703D03*
X45999Y1971450D03*
X50499Y1961550D03*
X43462Y1961160D03*
X78700Y74200D03*
Y70700D03*
X74999Y70550D03*
Y74050D03*
X74499Y80650D03*
Y84050D03*
X65999Y216050D03*
X65000Y455500D03*
X62503Y470946D03*
X66199Y475184D03*
Y469884D03*
X77499Y469550D03*
X62978Y486217D03*
X63067Y489616D03*
X66299Y490784D03*
Y485484D03*
X77999Y493050D03*
X77499Y502550D03*
X65599Y514250D03*
X63499Y538550D03*
Y533050D03*
X68000Y546500D03*
X72500Y545000D03*
X81251Y607249D03*
Y619251D03*
X82499Y627050D03*
X80499Y664550D03*
X74499Y662050D03*
X78499Y654050D03*
X76999Y664550D03*
X81999Y668050D03*
X65500Y817700D03*
X80500Y817000D03*
X76540Y850938D03*
X75500Y847700D03*
X68860Y838706D03*
X69499Y842950D03*
X63499Y843050D03*
X74220Y854150D03*
X72362Y849550D03*
X80699Y1004450D03*
Y1000450D03*
X72000Y1013400D03*
X63273Y1023974D03*
X66499Y1025050D03*
X75500Y1012261D03*
X65486Y1031515D03*
X80000Y1090500D03*
X74500Y1097550D03*
X79899Y1104550D03*
X74399Y1111550D03*
X76999Y1196550D03*
X78499Y1273550D03*
X78613Y1282664D03*
X78779Y1302664D03*
Y1312664D03*
X77758Y1357742D03*
X76000Y1431100D03*
X80043Y1544691D03*
X78600Y1561900D03*
X75000Y1561800D03*
X74400Y1574800D03*
X80400Y1571766D03*
X82329Y1568117D03*
X79000Y1555500D03*
X82429D03*
X74800Y1584700D03*
X78100Y1688189D03*
X74500Y1692000D03*
X74400Y1778100D03*
X80099Y1817250D03*
X80999Y1836550D03*
X93999Y58550D03*
X92900Y66128D03*
X92999Y86128D03*
X97499Y90050D03*
X92999Y96128D03*
X89603Y132629D03*
X86899Y130567D03*
X86599Y126750D03*
X95350Y204550D03*
X89800Y208550D03*
X96900Y510000D03*
X93200Y510500D03*
X95500Y513400D03*
X98900D03*
X83700Y529500D03*
X88999Y538050D03*
X104502Y530552D03*
X86199Y536025D03*
Y532250D03*
X89000Y816500D03*
X90000Y826000D03*
X90500Y831500D03*
X98700Y822550D03*
X98000Y833500D03*
X98700Y842600D03*
X92999Y868550D03*
X92499Y876550D03*
X94999Y901550D03*
X89469Y935588D03*
X85999Y940429D03*
X86399Y937050D03*
X89499Y942850D03*
X102100Y968500D03*
X99000Y965000D03*
X104600Y980500D03*
X90000Y993100D03*
X92600Y996100D03*
X88000Y1008500D03*
X101499Y1072550D03*
X103999Y1216863D03*
X102900Y1196050D03*
X103686Y1223863D03*
X101541Y1262607D03*
X101399Y1292550D03*
X102700Y1321363D03*
X102000Y1341000D03*
X91279Y1340642D03*
X86165Y1339050D03*
X86890Y1342860D03*
X101500Y1352000D03*
X89999Y1348050D03*
X86890Y1346635D03*
X102350Y1344500D03*
Y1348154D03*
X97229Y1373337D03*
X97000Y1377600D03*
X98599Y1491350D03*
X100699Y1471050D03*
X100499Y1479650D03*
X83932Y1544705D03*
X100800Y1536450D03*
X96200Y1550100D03*
X99899Y1539850D03*
X100000Y1546650D03*
X90324Y1538800D03*
X97499Y1554550D03*
X98144Y1534309D03*
X96999Y1558050D03*
X89373Y1561073D03*
X85600Y1561500D03*
X95499Y1665418D03*
X92900Y1678176D03*
X93999Y1703050D03*
X92873Y1708176D03*
X92479Y1718176D03*
X89306Y1746856D03*
X89499Y1753575D03*
X85341Y1752245D03*
X85194Y1748848D03*
X99199Y1761899D03*
X99999Y1753575D03*
X101399Y1784700D03*
X85599Y1797350D03*
X96600Y1826000D03*
X86649Y1817100D03*
X90000Y1827900D03*
X93500D03*
X97999Y1843050D03*
X112999Y124050D03*
X111790Y132259D03*
X115876Y125973D03*
Y130050D03*
X114900Y177900D03*
X122397Y252688D03*
X122799Y249150D03*
X124999Y246050D03*
X123378Y255944D03*
X107499Y497050D03*
X107526Y528996D03*
X109400Y543200D03*
X106000D03*
X105100Y600000D03*
X107000Y604800D03*
X125499Y635550D03*
Y638950D03*
X124999Y643050D03*
X110500Y790200D03*
X111100Y813400D03*
X111200Y799450D03*
X111207Y810001D03*
X110700Y795700D03*
X111089Y806603D03*
X110800Y803100D03*
X110499Y834550D03*
X106749Y934367D03*
X108441Y924705D03*
X108845Y931657D03*
X109099Y928250D03*
X108200Y963600D03*
X107300Y986000D03*
X107400Y992900D03*
X124100Y1047100D03*
X123999Y1054050D03*
Y1050650D03*
X120100Y1053200D03*
X116700Y1063500D03*
X112699Y1058974D03*
X105499Y1080550D03*
X106718Y1076050D03*
X105999Y1085800D03*
X121500Y1083600D03*
X121100Y1075300D03*
X117499Y1079300D03*
X105600Y1069500D03*
X124423Y1077523D03*
Y1081177D03*
X120749Y1093990D03*
X125900Y1091282D03*
X116249Y1102550D03*
X112999Y1103740D03*
X123999Y1102550D03*
X108999Y1102050D03*
X106999Y1194550D03*
X106162Y1205702D03*
X114999Y1210363D03*
X118999Y1219050D03*
X123970Y1221573D03*
X119399Y1298113D03*
X116999Y1288050D03*
X120507Y1317050D03*
X111499Y1311800D03*
X107999Y1307713D03*
X116499Y1328013D03*
X120507Y1328096D03*
X113000Y1341000D03*
X107228Y1330552D03*
X107500Y1340500D03*
X109228Y1337090D03*
Y1333315D03*
X119499Y1339050D03*
X113500Y1352000D03*
X110499Y1365050D03*
X109999Y1355050D03*
X112440Y1358196D03*
X112999Y1361550D03*
X121000Y1364000D03*
X113500Y1344500D03*
Y1348154D03*
X125100Y1366000D03*
X117390Y1426201D03*
X119507Y1423540D03*
X117390Y1429976D03*
X104935Y1440634D03*
X104999Y1444941D03*
X107328Y1438218D03*
X114499Y1432050D03*
X107999Y1448050D03*
X124290Y1469241D03*
X123808Y1465050D03*
X106999Y1454450D03*
X105099Y1459150D03*
X123999Y1473050D03*
X122199Y1476050D03*
X118499Y1694050D03*
X117499Y1706050D03*
X109499Y1712213D03*
X104999Y1708963D03*
X117249Y1712090D03*
X112753Y1716613D03*
X122642Y1704243D03*
X112562Y1720613D03*
X123749Y1711550D03*
X109499Y1743550D03*
X107499Y1736550D03*
X109399Y1739550D03*
X106999Y1746290D03*
X110099Y1759875D03*
X123393Y1870859D03*
X123592Y1874254D03*
X127999Y157050D03*
X147099Y245350D03*
X141499Y427550D03*
Y423050D03*
X135499Y517550D03*
X138999Y524213D03*
X137899Y545451D03*
X138416Y553500D03*
X140940Y561800D03*
X141300Y565900D03*
X127999Y645550D03*
X131400Y644600D03*
X144238Y645356D03*
X128725Y636626D03*
X128479Y640589D03*
X141773Y643013D03*
X144238Y649131D03*
X140499Y649350D03*
X134300Y646400D03*
X141500Y711000D03*
X137100Y1084800D03*
X140800Y1076300D03*
X137481Y1077557D03*
X137477Y1081177D03*
X132499Y1094550D03*
X138600Y1124600D03*
X130699Y1210653D03*
X135850Y1322250D03*
X125999Y1315550D03*
X132999Y1319550D03*
X142667Y1319218D03*
X143700Y1332500D03*
X133475Y1331200D03*
X140000Y1332600D03*
X138000Y1359025D03*
X129000Y1356500D03*
X142999Y1456373D03*
X139815Y1454438D03*
X139235Y1460973D03*
X127898Y1462441D03*
X142900Y1460000D03*
X133090Y1699959D03*
X128749Y1703300D03*
X131999Y1710050D03*
X141500Y1715500D03*
X135499Y1710150D03*
X141999Y1764550D03*
X137999Y1861497D03*
Y1865151D03*
X141101Y1866545D03*
X140999Y1859550D03*
X135999Y1881550D03*
X152499Y149550D03*
X154200Y168500D03*
X149400Y166400D03*
X149999Y243504D03*
Y239729D03*
X157440Y283924D03*
Y303924D03*
Y313924D03*
X165699Y428050D03*
X153459Y427494D03*
X154101Y445550D03*
X159600Y446399D03*
X163549Y517100D03*
X152000Y520813D03*
X163449Y521650D03*
X149000Y537500D03*
X150500Y545000D03*
X160932Y549468D03*
X150750Y540416D03*
X156500Y554000D03*
X157000Y573851D03*
X160824Y577000D03*
X161000Y639100D03*
X158885Y679436D03*
Y689436D03*
X158385Y719436D03*
X159500Y814700D03*
X165499Y815550D03*
X153500Y834600D03*
X154799Y838050D03*
X153499Y918550D03*
X163500Y937100D03*
X160399Y922850D03*
X152500Y960000D03*
X154749Y979149D03*
Y968249D03*
X164700Y1085400D03*
X159000Y1083000D03*
X157700Y1114948D03*
X157600Y1124948D03*
X149562Y1315987D03*
X147400Y1321600D03*
X148024Y1333525D03*
X150338Y1453958D03*
X152499Y1462940D03*
X157440Y1490460D03*
Y1500460D03*
Y1520460D03*
Y1530460D03*
X157400Y1596550D03*
X160200Y1598500D03*
X165575Y1676975D03*
X152633Y1677967D03*
X150999Y1713550D03*
X165900Y1790500D03*
X161900Y1793400D03*
X159421Y1925972D03*
X175999Y82428D03*
X174999Y79050D03*
X175499Y86572D03*
X176399Y94872D03*
X178999Y79050D03*
X186999Y99050D03*
X169999Y129050D03*
X188999Y120800D03*
X173499Y149050D03*
X173500Y166315D03*
X187699Y492850D03*
X173100Y483100D03*
X172499Y491053D03*
X176799Y493850D03*
X188000Y484500D03*
X171722Y513827D03*
X182499Y532550D03*
X168453Y527949D03*
X183499Y556100D03*
X172660Y815731D03*
X169106Y815865D03*
X174199Y841050D03*
X172500Y919294D03*
X172000Y931600D03*
X171100Y935000D03*
X171000Y939500D03*
X172000Y961000D03*
X170250Y948500D03*
X179499Y1275550D03*
X181000Y1365500D03*
X180500Y1369900D03*
X179999Y1655887D03*
X171999Y1662250D03*
X169600Y1682300D03*
X169100Y1685800D03*
X174250Y1694500D03*
X181100Y1682700D03*
X177900Y1690400D03*
X205938Y72528D03*
X201499Y104550D03*
X205499Y105550D03*
X207999Y109550D03*
X197899Y165075D03*
X199900Y554050D03*
X193549Y575875D03*
X200000Y818000D03*
X200539Y890300D03*
X200799Y896600D03*
X198924Y975975D03*
X199149Y1362900D03*
X194700Y1385700D03*
X193500Y1647000D03*
X201499Y1781050D03*
X194049Y1792600D03*
X210605Y70692D03*
X210685Y74725D03*
X215138Y72559D03*
X210634Y66863D03*
X210638Y62959D03*
X225499Y68550D03*
X210738Y82159D03*
Y78459D03*
X230749Y76300D03*
X213499Y104650D03*
X223499Y108150D03*
X218499Y190550D03*
X225298Y281114D03*
X213499Y283864D03*
X214063Y318114D03*
X213400Y355300D03*
X224998Y357049D03*
X220000Y516400D03*
X216999Y686550D03*
X213999Y725050D03*
X230849Y726050D03*
X228999Y765550D03*
X218224Y765325D03*
X211750Y894600D03*
X229562Y904113D03*
X215499Y905550D03*
X221800Y1069300D03*
X221300Y1083238D03*
X229800Y1073600D03*
X226800Y1093400D03*
X224750Y1483950D03*
X229025Y1471576D03*
X227814Y1887513D03*
X223436Y1890465D03*
X229800Y1875700D03*
X218100Y1886400D03*
X214999Y1909550D03*
X213562Y1926113D03*
X220062Y1931113D03*
X213138Y1952703D03*
X210999Y1942050D03*
X246999Y51550D03*
X246499Y42550D03*
X246999Y69550D03*
Y60550D03*
X246499Y86050D03*
Y80550D03*
X245499Y100550D03*
X233749Y110800D03*
X237899Y107050D03*
X247800Y269700D03*
X250300Y275100D03*
X250400Y283100D03*
X239600Y278600D03*
X231800Y318414D03*
X233998Y357549D03*
X239400Y357400D03*
X246800Y677100D03*
X249700Y682500D03*
X238500Y680800D03*
X249800Y689900D03*
X252499Y726050D03*
X241600Y765700D03*
X236800Y765800D03*
X233500Y1066100D03*
X242000Y1066000D03*
X247500Y1085500D03*
X251500Y1136700D03*
X241000Y1469600D03*
X233700Y1481600D03*
X232650Y1493450D03*
X231800Y1887100D03*
X232314Y1890513D03*
X236225Y1883125D03*
X231999Y1914050D03*
X249600Y1896800D03*
X249499Y1928050D03*
X240964Y1934113D03*
X253999Y44050D03*
X253871Y291410D03*
X252935Y319114D03*
X254499Y697700D03*
X255000Y1125700D03*
X256000Y1133000D03*
X269500Y1135500D03*
X261999Y1516050D03*
X257499Y1911050D03*
X264499Y1964050D03*
X291999Y94050D03*
X282800Y87500D03*
X293999Y293550D03*
X284999Y338650D03*
X281499Y338550D03*
X294500Y339000D03*
X279939Y728610D03*
X285499Y745050D03*
X282099D03*
X292999Y743650D03*
X277039Y740300D03*
X282500Y1135000D03*
X295000Y1513000D03*
X289999Y1554650D03*
X293700Y1553351D03*
X276039Y1551300D03*
X283499Y1556050D03*
X279999D03*
X291400Y1561500D03*
X285499Y1930050D03*
X288709Y1948042D03*
X284999Y1947691D03*
X280689Y1942710D03*
X296099Y17100D03*
X305099Y17000D03*
X311400Y17100D03*
X308999Y87050D03*
X297499Y97550D03*
X315800Y100500D03*
X298800Y333000D03*
X301249Y346050D03*
X313039Y352350D03*
X308999Y716450D03*
X315999Y718950D03*
X298000Y743500D03*
X310999Y757050D03*
X314999Y1527550D03*
X297800Y1561600D03*
X312999Y1566050D03*
X310249Y1569800D03*
X313499Y1919050D03*
X310499Y1957050D03*
X315999Y1958550D03*
X317000Y17300D03*
X324800Y89400D03*
X323400Y105200D03*
X326499Y334054D03*
Y337454D03*
X321900Y364600D03*
X327999Y740550D03*
X323249Y749010D03*
X327749Y744050D03*
X324959Y766750D03*
X329499Y801550D03*
X330540Y795509D03*
X320499Y798050D03*
X326500Y1550200D03*
X324000Y1562500D03*
X330300Y1561200D03*
X323999Y1577250D03*
X325221Y1927272D03*
X331622Y1944767D03*
X329999Y1952273D03*
X332103Y1948133D03*
X327100Y1966472D03*
X343499Y31650D03*
X354999Y72050D03*
X343499Y60150D03*
X341499Y63050D03*
Y67110D03*
X357503Y77043D03*
X344520Y406329D03*
X350499Y597300D03*
Y715050D03*
X340699Y1046086D03*
X345499Y1096550D03*
X345424Y1310050D03*
X347324Y1524000D03*
X354500Y1559500D03*
X349774Y1582900D03*
X354000Y1584900D03*
X353499Y1710450D03*
X348499Y1762050D03*
X342999Y1947409D03*
X342621Y1943409D03*
X358999Y61550D03*
X374499Y77550D03*
X365499Y86550D03*
X371999Y549300D03*
X375999Y698550D03*
X371500Y880600D03*
X364499Y1099050D03*
X372999Y1123550D03*
X370149Y1320050D03*
X366149Y1554050D03*
X377900Y1703800D03*
X398799Y36152D03*
X381999Y50150D03*
X382339Y41610D03*
X381999Y53550D03*
X394199Y45050D03*
X381999Y57050D03*
X385999Y78050D03*
X400499Y406329D03*
X394649Y630600D03*
X390999Y1514398D03*
Y1517798D03*
X385499Y1735050D03*
X401499Y80550D03*
X402499Y1476850D03*
X400999Y1575550D03*
X645549Y1815134D03*
X644360Y1819137D03*
X659549Y1810634D03*
X690249Y1805634D03*
X707600Y1815600D03*
X711652Y1822109D03*
X711848Y1825504D03*
X732549Y1806634D03*
X733149Y1798634D03*
X733049Y1814134D03*
X752999Y746842D03*
X757499Y745342D03*
Y1079550D03*
X755600Y1149800D03*
X758499Y1371050D03*
X757999Y1484050D03*
X758199Y1553650D03*
X755000Y1825000D03*
X758499Y1893550D03*
X759114Y1957673D03*
X770999Y302050D03*
Y290050D03*
Y295550D03*
X763571Y295622D03*
X777999Y296050D03*
X772499Y323050D03*
X772873Y326924D03*
X760778Y345050D03*
X768178Y333964D03*
X780499Y330050D03*
X771105Y722789D03*
X766499Y732842D03*
X762999Y734550D03*
X769999Y733050D03*
X771999Y1124550D03*
X772499Y1130050D03*
X779499Y1131050D03*
X767083Y1134550D03*
X768199Y1138590D03*
X774542Y1530050D03*
X774577Y1533796D03*
X771225Y1539474D03*
X767936Y1540336D03*
X774500Y1788000D03*
X770999Y1820550D03*
X771499Y1936550D03*
X767999Y1945173D03*
X764908Y1946592D03*
X771499Y1940050D03*
X785499Y291050D03*
X786978Y298529D03*
X791499Y333050D03*
X789999Y336550D03*
X784499Y334050D03*
X781999Y725550D03*
X788999Y736050D03*
X791999Y733050D03*
X784939Y733550D03*
X792154Y1135926D03*
X784439Y1136550D03*
X789499Y1138050D03*
X784499Y1529050D03*
X784577Y1535628D03*
X791499Y1543550D03*
X793999Y1541050D03*
X788000Y1788000D03*
X793000Y1803500D03*
X795849Y1805500D03*
X791999Y1819050D03*
X783499Y1827050D03*
X802499Y1951550D03*
X800431Y1941193D03*
X785939Y1946800D03*
X792499Y1949050D03*
X794499Y1941050D03*
X782999Y1937050D03*
X802099Y1961950D03*
X820749Y163850D03*
X813249Y163800D03*
X821999Y193116D03*
X809940Y264940D03*
X822100Y261700D03*
Y279500D03*
X816700Y274300D03*
X820600Y664300D03*
X808660Y667540D03*
X813200Y675900D03*
X807000Y1072900D03*
X815400Y1078800D03*
X803199Y1151850D03*
X822100Y1466800D03*
X809960Y1478040D03*
X814700Y1486300D03*
X804899Y1556950D03*
X812000Y1799500D03*
X821249Y1791250D03*
X811000Y1793000D03*
X822499Y1815164D03*
X807000Y1822300D03*
X803500Y1822708D03*
X822700Y1871100D03*
X810900Y1882440D03*
X805900Y1887560D03*
X841499Y135550D03*
X827499Y163550D03*
X839249Y164050D03*
X829917Y216200D03*
X833576Y215432D03*
X837999Y219550D03*
X842499Y280924D03*
X827500Y274500D03*
X836500Y274950D03*
X827499Y313424D03*
X829800Y666650D03*
X835150Y677650D03*
X825700Y1083100D03*
X825800Y1072300D03*
X827700Y1487600D03*
X836625Y1487400D03*
X828500Y1877800D03*
X834799Y1946950D03*
X861999Y146550D03*
X854400Y264600D03*
X847878Y250040D03*
X851278Y249974D03*
X847450Y246666D03*
X850999Y246550D03*
X858478Y274050D03*
X865499Y288050D03*
X851172Y655432D03*
X847772Y655370D03*
X851197Y652032D03*
X847493Y651981D03*
X852696Y671197D03*
X850833Y1061441D03*
X847233Y1061492D03*
X847355Y1058094D03*
X851042Y1058047D03*
X852333Y1077716D03*
X860133Y1084142D03*
X864499Y1128750D03*
X860799Y1358925D03*
X861849Y1376050D03*
X848888Y1466402D03*
X852288Y1466346D03*
X848861Y1462463D03*
X852429Y1462948D03*
X854327Y1477550D03*
X858827Y1485696D03*
X863699Y1501250D03*
X862800Y1712700D03*
X851500Y1821400D03*
X849375Y1824982D03*
X854905Y1825583D03*
X853499Y1871036D03*
X850099Y1871056D03*
X854480Y1867578D03*
X849999Y1867550D03*
X863788Y1866953D03*
X865501Y1858747D03*
X859314Y1891365D03*
X854814Y1883550D03*
X863699Y1906450D03*
X857099Y1917650D03*
X882499Y147050D03*
X867500Y163924D03*
X867576Y159924D03*
X878078Y240103D03*
Y243878D03*
X874928Y238822D03*
X874790Y244748D03*
X871999Y283924D03*
X872136Y273924D03*
X886600Y303924D03*
X868799Y294750D03*
X867899Y321550D03*
X886200Y313924D03*
X868299Y336150D03*
X879750Y570550D03*
X879950Y565050D03*
X878596Y645573D03*
X874999Y644550D03*
X878596Y649348D03*
X875270Y650059D03*
X883083Y979183D03*
X879708Y971892D03*
X878233Y1051095D03*
X877964Y1054485D03*
X874733Y1055792D03*
X874999Y1049550D03*
X872086Y1084948D03*
X871999Y1094948D03*
X871499Y1124948D03*
X872086Y1114948D03*
X866700Y1379796D03*
X866596Y1375796D03*
X878054Y1456450D03*
X877853Y1459991D03*
X874499Y1460550D03*
X874986Y1454983D03*
X872086Y1490460D03*
X871999Y1500460D03*
Y1520460D03*
X872086Y1530460D03*
X867523Y1542821D03*
X867199Y1535150D03*
X886439Y1717600D03*
X873800Y1733600D03*
X879700Y1786300D03*
X879664Y1782213D03*
X866914Y1861840D03*
Y1865615D03*
X871921Y1905972D03*
X871421Y1895972D03*
X872086Y1925972D03*
Y1935972D03*
X901499Y92050D03*
X897555Y90494D03*
X898999Y99050D03*
X902499Y110550D03*
X898999D03*
X907499Y131800D03*
X896999Y141550D03*
X902999Y556050D03*
X900499Y962100D03*
X900999Y979050D03*
X889800Y1711500D03*
X923761Y85550D03*
X928561Y95181D03*
X928428Y83714D03*
X928508Y87747D03*
X928561Y91481D03*
X928457Y79885D03*
X928461Y75981D03*
X916499Y115050D03*
X926999D03*
Y122050D03*
X910999Y124550D03*
X916499Y172550D03*
X922049Y574375D03*
Y978575D03*
X921549Y1788475D03*
X917499Y1796550D03*
X932961Y85581D03*
X943499Y82550D03*
X930999Y115550D03*
X938499D03*
X946899Y122550D03*
X937999Y122050D03*
X934499Y118750D03*
X939549Y175175D03*
X961499Y93350D03*
X958999Y96050D03*
X961499Y100050D03*
X966499Y552050D03*
X965999Y954550D03*
X965150Y1639500D03*
X961702Y1636102D03*
X969600Y1638300D03*
X967600Y1651100D03*
X971558Y1646500D03*
X981200Y1618002D03*
X986400Y1639302D03*
X987100Y1624900D03*
X981200Y1625800D03*
X990425Y1633898D03*
X987029Y1634075D03*
X977500Y1660500D03*
X989502Y1646000D03*
X988800Y1658300D03*
X981500Y1653000D03*
X980800Y1659600D03*
X982050Y1649302D03*
X978000Y1668000D03*
X989000Y1663802D03*
X987200Y1675600D03*
X989900Y1678800D03*
X974000Y1670700D03*
X984211Y1667500D03*
G54D14*
X68898Y17047D03*
Y190275D03*
Y422559D03*
Y595787D03*
Y828071D03*
Y1001299D03*
Y1233583D03*
Y1406811D03*
Y1639095D03*
Y1812323D03*
X167323Y179803D03*
Y353031D03*
Y585315D03*
Y758543D03*
Y990827D03*
Y1164055D03*
Y1396339D03*
Y1569567D03*
Y1801851D03*
Y1975079D03*
X895669Y179803D03*
Y353031D03*
Y585315D03*
Y758543D03*
Y990827D03*
Y1164055D03*
Y1396339D03*
Y1569567D03*
Y1801851D03*
Y1975079D03*
G54D15*
X129921Y17716D03*
X994093Y1889751D03*
G54D16*
G01X-87137Y-139897D02*
Y-107897D01*
G01X-75137Y-123897D02*
G02I-12000J0D01*
G01X-80287D02*
G02I-6850J0D01*
G01X-71137D02*
X-103137D01*
G01X-71137Y-139897D02*
Y-219897D01*
G01D02*
X1129963D01*
G01X-71137Y-175397D02*
X1129963D01*
G01X-71137Y-139897D02*
X1129963D01*
G01X81251Y607249D02*
Y608151D01*
X127868Y654768D01*
X153326D01*
X155300Y652794D01*
Y641896D01*
X154999Y641595D01*
Y608025D01*
X145499Y598525D01*
Y568499D01*
X142900Y565900D01*
X141300D01*
G01X81251Y619251D02*
X86451D01*
X125168Y657968D01*
X154652D01*
X158500Y654120D01*
Y640570D01*
X158199Y640269D01*
Y606699D01*
X148699Y597199D01*
Y562900D01*
X139299Y553500D01*
X138416D01*
G01X159186Y946117D02*
X154503Y950800D01*
X141200D01*
X111500Y980500D01*
X104600D01*
G01X170250Y948500D02*
X168521D01*
X163021Y954000D01*
X145526D01*
X114162Y985364D01*
X107936D01*
X107300Y986000D01*
G01X107400Y992900D02*
Y992700D01*
X110624Y989476D01*
X114576D01*
X146852Y957200D01*
X164347D01*
X168097Y953450D01*
X169826D01*
X173450Y949826D01*
Y947150D01*
X171000Y944700D01*
Y939500D01*
G01X233500Y1066100D02*
Y1086700D01*
X226800Y1093400D01*
G01X342463Y-139897D02*
Y-219897D01*
G01X479963Y-139897D02*
Y-219897D01*
G01X594963Y-139897D02*
Y-219897D01*
G01X633837Y1807384D02*
Y1788712D01*
X637999Y1784550D01*
X759345D01*
X767159Y1792364D01*
G01X762463Y-139897D02*
Y-219897D01*
G01X932463Y-139897D02*
Y-219897D01*
G01X1129963Y-139897D02*
Y-219897D01*
G01X1157963Y-123897D02*
G02I-12000J0D01*
G01X1152813D02*
G02I-6850J0D01*
G01X1161963D02*
X1129963D01*
G01X1145963Y-139897D02*
Y-107897D01*
G54D17*
G01X35800Y1018000D02*
Y1023241D01*
X29531Y1029510D01*
G54D18*
G01X43499Y657550D02*
X51499D01*
X161999Y768050D01*
G01X148024Y1333525D02*
X167999Y1313550D01*
X168062D01*
X175499Y1306113D01*
G54D19*
G01X17720Y1893930D02*
Y1903132D01*
G01D02*
Y1912334D01*
G01X8518Y1903132D02*
X17720D01*
G01D02*
X26922D01*
G01X29531Y300347D02*
Y309549D01*
G01D02*
Y318751D01*
G01X20329Y309549D02*
X29531D01*
G01D02*
X38733D01*
G01X29531Y1029510D02*
Y1038712D01*
G01Y1029510D02*
X36238Y1036217D01*
G01X62346Y426961D02*
X68898Y422559D01*
G01Y12645D02*
Y17047D01*
G01D02*
Y21449D01*
G01X62346Y17047D02*
X68898D01*
G01D02*
X75450D01*
G01X68898Y185873D02*
Y190275D01*
G01D02*
Y194677D01*
G01X62346Y190275D02*
X68898D01*
G01D02*
X75450D01*
G01X68898Y422559D02*
Y426961D01*
G01Y591385D02*
Y595787D01*
G01D02*
Y600189D01*
G01X62346Y595787D02*
X68898D01*
G01D02*
X75450D01*
G01X68898Y823669D02*
Y828071D01*
G01D02*
Y832473D01*
G01X62346Y828071D02*
X68898D01*
G01D02*
X75450D01*
G01X68898Y996897D02*
Y1001299D01*
G01D02*
Y1005701D01*
G01Y1001299D02*
X75450D01*
G01X68898Y1229181D02*
Y1233583D01*
G01D02*
Y1237985D01*
G01X62346Y1233583D02*
X68898D01*
G01D02*
X75450D01*
G01X68898Y1402409D02*
Y1406811D01*
G01D02*
Y1411213D01*
G01Y1406811D02*
X75450D01*
G01X68898Y1634693D02*
Y1639095D01*
G01D02*
Y1643497D01*
G01Y1639095D02*
X75450D01*
G01X68898Y1807921D02*
Y1812323D01*
G01X62346D02*
X68898D01*
G01X119869Y17716D02*
X129921D01*
G01Y7664D02*
Y17716D01*
G01D02*
X139973D01*
G01X167323Y175401D02*
Y179803D01*
G01D02*
Y184205D01*
G01X160771Y179803D02*
X167323D01*
G01D02*
X173875D01*
G01X167323Y348629D02*
Y353031D01*
G01D02*
Y357433D01*
G01X160771Y353031D02*
X167323D01*
G01D02*
X173875D01*
G01X167323Y580913D02*
Y585315D01*
G01D02*
Y589717D01*
G01Y585315D02*
X173875D01*
G01X167323Y754141D02*
Y758543D01*
G01D02*
Y762945D01*
G01X160771Y758543D02*
X167323D01*
G01D02*
X173875D01*
G01X167323Y986425D02*
Y990827D01*
G01D02*
Y995229D01*
G01X160771Y990827D02*
X167323D01*
G01D02*
X173875D01*
G01X167323Y1159653D02*
Y1164055D01*
G01D02*
Y1168457D01*
G01X160771Y1164055D02*
X167323D01*
G01D02*
X173875D01*
G01X167323Y1391937D02*
Y1396339D01*
G01D02*
Y1400741D01*
G01X160771Y1396339D02*
X167323D01*
G01D02*
X173875D01*
G01X167323Y1565165D02*
Y1569567D01*
G01D02*
Y1573969D01*
G01X160771Y1569567D02*
X167323D01*
G01D02*
X173875D01*
G01X167323Y1797449D02*
Y1801851D01*
G01D02*
Y1806253D01*
G01X160771Y1801851D02*
X167323D01*
G01D02*
X173875D01*
G01X167323Y1970677D02*
Y1975079D01*
G01D02*
Y1979481D01*
G01X160771Y1975079D02*
X167323D01*
G01D02*
X173875D01*
G01X271657Y258497D02*
Y267699D01*
G01D02*
Y276901D01*
G01X262455Y267699D02*
X271657D01*
G01D02*
X280859D01*
G01X271657Y664008D02*
Y673210D01*
G01D02*
Y682412D01*
G01X262455Y673210D02*
X271657D01*
G01Y1069520D02*
Y1078722D01*
G01D02*
Y1087924D01*
G01X262455Y1078722D02*
X271657D01*
G01D02*
X280859D01*
G01X271657Y1475032D02*
Y1484234D01*
G01D02*
Y1493436D01*
G01X262455Y1484234D02*
X271657D01*
G01D02*
X280859D01*
G01X271657Y1889746D02*
Y1898948D01*
G01X262455Y1889746D02*
X271657D01*
G01X895669Y175401D02*
Y179803D01*
G01D02*
Y184205D01*
G01X889117Y179803D02*
X895669D01*
G01D02*
X902221D01*
G01X895669Y348629D02*
Y353031D01*
G01D02*
Y357433D01*
G01X889117Y353031D02*
X895669D01*
G01D02*
X902221D01*
G01X895669Y580913D02*
Y585315D01*
G01D02*
Y589717D01*
G01X889117Y585315D02*
X895669D01*
G01D02*
X902221D01*
G01X895669Y754141D02*
Y758543D01*
G01D02*
Y762945D01*
G01X889117Y758543D02*
X895669D01*
G01D02*
X902221D01*
G01X895669Y986425D02*
Y990827D01*
G01D02*
Y995229D01*
G01X889117Y990827D02*
X895669D01*
G01Y1159653D02*
Y1164055D01*
G01D02*
Y1168457D01*
G01X889117Y1164055D02*
X895669D01*
G01Y1391937D02*
Y1396339D01*
G01D02*
Y1400741D01*
G01X889117Y1396339D02*
X895669D01*
G01Y1565165D02*
Y1569567D01*
G01D02*
Y1573969D01*
G01X889117Y1569567D02*
X895669D01*
G01D02*
X902221D01*
G01X895669Y1797449D02*
Y1801851D01*
G01D02*
Y1806253D01*
G01X889117Y1801851D02*
X895669D01*
G01D02*
X902221D01*
G01X895669Y1970677D02*
Y1975079D01*
G01D02*
Y1979481D01*
G01X889117Y1975079D02*
X895669D01*
G01D02*
X902221D01*
G01X984896Y149588D02*
X994098D01*
G01X984896Y673210D02*
X994098D01*
G01X984896Y1068880D02*
X994098D01*
G01X984041Y1889751D02*
X994093D01*
G01X994098Y140386D02*
Y149588D01*
G01D02*
Y158790D01*
G01Y149588D02*
X1003300D01*
G01X994098Y664008D02*
Y673210D01*
G01D02*
Y682412D01*
G01Y673210D02*
X1003300D01*
G01X994098Y1059678D02*
Y1068880D01*
G01D02*
Y1078082D01*
G01Y1068880D02*
X1003300D01*
G01X994093Y1879699D02*
Y1889751D01*
G01D02*
Y1899803D01*
G01Y1889751D02*
X1004145D01*
M02*
